FILE_TYPE = MACRO_DRAWING;
SET COLOR_WIRE YELLOW;
SET COLOR_PROP ORANGE;
SET COLOR_DOT WHITE;
SET COLOR_ARC YELLOW;
SET COLOR_BODY GREEN;
SET COLOR_NOTE PURPLE;
SET PROP_DISPLAY VALUE;
SET PAGE_NUMBER P349;
FORCEADD Q_RES..1
(-525 2100);
FORCEPROP 1 LAST LOCATION R1321
J 0
(-700 2100);
DISPLAY 0.489362 (-700 2100);
PAINT SKYBLUE (-700 2100);
FORCEPROP 0 LAST $SEC 1
J 0
(-325 2125);
DISPLAY 0.680851 (-325 2125);
PAINT MONO (-325 2125);
DISPLAY INVISIBLE (-325 2125);
FORCEPROP 0 LAST CDS_SEC 1
J 0
(-325 2125);
DISPLAY 0.680851 (-325 2125);
DISPLAY INVISIBLE (-325 2125);
FORCEPROP 1 LASTPIN (-625 2100) $PN 1
J 0
(-613 2112);
DISPLAY 0.489362 (-613 2112);
PAINT MONO (-613 2112);
FORCEPROP 1 LASTPIN (-425 2100) $PN 2
J 0
(-463 2112);
DISPLAY 0.489362 (-463 2112);
PAINT MONO (-463 2112);
FORCEPROP 1 LAST VALUE 33
J 2
(-325 2100);
DISPLAY 0.489362 (-325 2100);
PAINT SKYBLUE (-325 2100);
FORCEPROP 1 LAST PACK_TYPE 0402LF
J 0
(-475 2025);
DISPLAY 0.489362 (-475 2025);
PAINT SKYBLUE (-475 2025);
DISPLAY INVISIBLE (-475 2025);
FORCEPROP 1 LAST TOLERANCE 5%
J 0
(-550 2025);
DISPLAY 0.489362 (-550 2025);
PAINT SKYBLUE (-550 2025);
DISPLAY INVISIBLE (-550 2025);
FORCEPROP 1 LAST MATERIAL CHIP
J 0
(-100 2025);
DISPLAY 0.489362 (-100 2025);
PAINT SKYBLUE (-100 2025);
DISPLAY INVISIBLE (-100 2025);
FORCEPROP 1 LAST WATTAGE 1/16W
J 2
(-125 2025);
DISPLAY 0.489362 (-125 2025);
PAINT SKYBLUE (-125 2025);
DISPLAY INVISIBLE (-125 2025);
FORCEPROP 2 LAST CDS_LIB pure_quanta
J 0
(-525 2100);
DISPLAY INVISIBLE (-525 2100);
FORCEPROP 1 LAST PART_NUMBER CS03302JB10
J 0
(-500 2150);
DISPLAY 0.489362 (-500 2150);
PAINT SKYBLUE (-500 2150);
DISPLAY INVISIBLE (-500 2150);
FORCEPROP 1 LAST PATH I10
J 0
(-575 2250);
DISPLAY 0.978723 (-575 2250);
PAINT WHITE (-575 2250);
DISPLAY INVISIBLE (-575 2250);
FORCEADD OFFPAGE..5
(3050 5025);
FORCEPROP 2 LAST $XR1 160 
J 0
(2645 5025);
DISPLAY 0.638298 (2645 5025);
PAINT MONO (2645 5025);
FORCEPROP 2 LAST $XR0 150 
J 0
(2765 5025);
DISPLAY 0.638298 (2765 5025);
PAINT MONO (2765 5025);
FORCEPROP 2 LAST CDS_LIB standard
J 0
(3050 5025);
PAINT MONO (3050 5025);
DISPLAY INVISIBLE (3050 5025);
FORCEPROP 1 LAST OFFPAGE TRUE
J 0
(3375 4900);
DISPLAY 0.872340 (3375 4900);
PAINT GREEN (3375 4900);
DISPLAY INVISIBLE (3375 4900);
FORCEPROP 1 LAST COMMENT_BODY TRUE
J 0
(3150 4950);
DISPLAY 0.872340 (3150 4950);
PAINT PEACH (3150 4950);
DISPLAY INVISIBLE (3150 4950);
FORCEPROP 2 LAST PATH I100
J 0
(3100 5100);
DISPLAY 0.680851 (3100 5100);
DISPLAY INVISIBLE (3100 5100);
FORCEADD OFFPAGE..5
(3050 5225);
FORCEPROP 2 LAST $XR1 160 
J 0
(2645 5225);
DISPLAY 0.638298 (2645 5225);
PAINT MONO (2645 5225);
FORCEPROP 2 LAST $XR0 150 
J 0
(2765 5225);
DISPLAY 0.638298 (2765 5225);
PAINT MONO (2765 5225);
FORCEPROP 2 LAST CDS_LIB standard
J 0
(3050 5225);
PAINT MONO (3050 5225);
DISPLAY INVISIBLE (3050 5225);
FORCEPROP 1 LAST OFFPAGE TRUE
J 0
(3375 5100);
DISPLAY 0.872340 (3375 5100);
PAINT GREEN (3375 5100);
DISPLAY INVISIBLE (3375 5100);
FORCEPROP 1 LAST COMMENT_BODY TRUE
J 0
(3150 5150);
DISPLAY 0.872340 (3150 5150);
PAINT PEACH (3150 5150);
DISPLAY INVISIBLE (3150 5150);
FORCEPROP 2 LAST PATH I101
J 0
(3100 5300);
DISPLAY 0.680851 (3100 5300);
DISPLAY INVISIBLE (3100 5300);
FORCEADD OFFPAGE..5
(3050 5275);
FORCEPROP 2 LAST $XR1 160 
J 0
(2645 5275);
DISPLAY 0.638298 (2645 5275);
PAINT MONO (2645 5275);
FORCEPROP 2 LAST $XR0 150 
J 0
(2765 5275);
DISPLAY 0.638298 (2765 5275);
PAINT MONO (2765 5275);
FORCEPROP 2 LAST CDS_LIB standard
J 0
(3050 5275);
PAINT MONO (3050 5275);
DISPLAY INVISIBLE (3050 5275);
FORCEPROP 1 LAST OFFPAGE TRUE
J 0
(3375 5150);
DISPLAY 0.872340 (3375 5150);
PAINT GREEN (3375 5150);
DISPLAY INVISIBLE (3375 5150);
FORCEPROP 1 LAST COMMENT_BODY TRUE
J 0
(3150 5200);
DISPLAY 0.872340 (3150 5200);
PAINT PEACH (3150 5200);
DISPLAY INVISIBLE (3150 5200);
FORCEPROP 2 LAST PATH I102
J 0
(3100 5350);
DISPLAY 0.680851 (3100 5350);
DISPLAY INVISIBLE (3100 5350);
FORCEADD OFFPAGE..2
(3600 5775);
FORCEPROP 2 LAST $XR0 234 
J 0
(3789 5775);
DISPLAY 0.638298 (3789 5775);
PAINT MONO (3789 5775);
FORCEPROP 2 LAST CDS_LIB standard
J 0
(3600 5775);
PAINT MONO (3600 5775);
DISPLAY INVISIBLE (3600 5775);
FORCEPROP 1 LAST OFFPAGE TRUE
J 0
(3925 5650);
DISPLAY 1.170213 (3925 5650);
PAINT GREEN (3925 5650);
DISPLAY INVISIBLE (3925 5650);
FORCEPROP 1 LAST COMMENT_BODY TRUE
J 0
(3555 5680);
DISPLAY 1.170213 (3555 5680);
PAINT GREEN (3555 5680);
DISPLAY INVISIBLE (3555 5680);
FORCEPROP 2 LAST PATH I103
J 0
(3800 5825);
DISPLAY 0.680851 (3800 5825);
DISPLAY INVISIBLE (3800 5825);
FORCEADD OFFPAGE..3
(3600 5725);
FORCEPROP 2 LAST $XR0 234 
J 0
(3814 5725);
DISPLAY 0.638298 (3814 5725);
PAINT MONO (3814 5725);
FORCEPROP 2 LAST CDS_LIB standard
J 0
(3600 5725);
PAINT MONO (3600 5725);
DISPLAY INVISIBLE (3600 5725);
FORCEPROP 1 LAST OFFPAGE TRUE
J 0
(3925 5600);
DISPLAY 0.872340 (3925 5600);
DISPLAY INVISIBLE (3925 5600);
FORCEPROP 1 LAST COMMENT_BODY TRUE
J 0
(3550 5625);
DISPLAY 0.872340 (3550 5625);
PAINT GREEN (3550 5625);
DISPLAY INVISIBLE (3550 5625);
FORCEPROP 2 LAST PATH I104
J 0
(3825 5775);
DISPLAY 0.680851 (3825 5775);
DISPLAY INVISIBLE (3825 5775);
FORCEADD OFFPAGE..2
(3625 6075);
FORCEPROP 2 LAST $XR0 80 
J 0
(3814 6075);
DISPLAY 0.638298 (3814 6075);
PAINT MONO (3814 6075);
FORCEPROP 2 LAST CDS_LIB standard
J 0
(3625 6075);
DISPLAY INVISIBLE (3625 6075);
FORCEPROP 1 LAST OFFPAGE TRUE
J 0
(3950 5950);
DISPLAY 1.170213 (3950 5950);
PAINT GREEN (3950 5950);
DISPLAY INVISIBLE (3950 5950);
FORCEPROP 1 LAST COMMENT_BODY TRUE
J 0
(3580 5980);
DISPLAY 1.170213 (3580 5980);
PAINT GREEN (3580 5980);
DISPLAY INVISIBLE (3580 5980);
FORCEPROP 2 LAST PATH I105
J 0
(3825 6125);
DISPLAY 0.680851 (3825 6125);
DISPLAY INVISIBLE (3825 6125);
FORCEADD OFFPAGE..3
(3625 6025);
FORCEPROP 2 LAST $XR0 80 
J 0
(3839 6025);
DISPLAY 0.638298 (3839 6025);
PAINT MONO (3839 6025);
FORCEPROP 2 LAST CDS_LIB standard
J 0
(3625 6025);
DISPLAY INVISIBLE (3625 6025);
FORCEPROP 1 LAST OFFPAGE TRUE
J 0
(3950 5900);
DISPLAY 0.872340 (3950 5900);
DISPLAY INVISIBLE (3950 5900);
FORCEPROP 1 LAST COMMENT_BODY TRUE
J 0
(3575 5925);
DISPLAY 0.872340 (3575 5925);
PAINT GREEN (3575 5925);
DISPLAY INVISIBLE (3575 5925);
FORCEPROP 2 LAST PATH I106
J 0
(3850 6075);
DISPLAY 0.680851 (3850 6075);
DISPLAY INVISIBLE (3850 6075);
FORCEADD OFFPAGE..2
(3600 6775);
FORCEPROP 2 LAST $XR0 263 
J 0
(3789 6775);
DISPLAY 0.638298 (3789 6775);
PAINT MONO (3789 6775);
FORCEPROP 2 LAST CDS_LIB standard
J 0
(3600 6775);
PAINT MONO (3600 6775);
DISPLAY INVISIBLE (3600 6775);
FORCEPROP 1 LAST OFFPAGE TRUE
J 0
(3925 6650);
DISPLAY 1.170213 (3925 6650);
PAINT GREEN (3925 6650);
DISPLAY INVISIBLE (3925 6650);
FORCEPROP 1 LAST COMMENT_BODY TRUE
J 0
(3555 6680);
DISPLAY 1.170213 (3555 6680);
PAINT GREEN (3555 6680);
DISPLAY INVISIBLE (3555 6680);
FORCEPROP 2 LAST PATH I107
J 0
(3800 6825);
DISPLAY 0.680851 (3800 6825);
DISPLAY INVISIBLE (3800 6825);
FORCEADD OFFPAGE..3
(3600 6725);
FORCEPROP 2 LAST $XR0 263 
J 0
(3814 6725);
DISPLAY 0.638298 (3814 6725);
PAINT MONO (3814 6725);
FORCEPROP 2 LAST CDS_LIB standard
J 0
(3600 6725);
PAINT MONO (3600 6725);
DISPLAY INVISIBLE (3600 6725);
FORCEPROP 1 LAST OFFPAGE TRUE
J 0
(3925 6600);
DISPLAY 0.872340 (3925 6600);
DISPLAY INVISIBLE (3925 6600);
FORCEPROP 1 LAST COMMENT_BODY TRUE
J 0
(3550 6625);
DISPLAY 0.872340 (3550 6625);
PAINT GREEN (3550 6625);
DISPLAY INVISIBLE (3550 6625);
FORCEPROP 2 LAST PATH I108
J 0
(3825 6775);
DISPLAY 0.680851 (3825 6775);
DISPLAY INVISIBLE (3825 6775);
FORCEADD OFFPAGE..2
(3625 6350);
FORCEPROP 2 LAST $XR0 80 
J 0
(3814 6350);
DISPLAY 0.638298 (3814 6350);
PAINT MONO (3814 6350);
FORCEPROP 2 LAST CDS_LIB standard
J 0
(3625 6350);
DISPLAY INVISIBLE (3625 6350);
FORCEPROP 1 LAST OFFPAGE TRUE
J 0
(3950 6225);
DISPLAY 1.170213 (3950 6225);
PAINT GREEN (3950 6225);
DISPLAY INVISIBLE (3950 6225);
FORCEPROP 1 LAST COMMENT_BODY TRUE
J 0
(3580 6255);
DISPLAY 1.170213 (3580 6255);
PAINT GREEN (3580 6255);
DISPLAY INVISIBLE (3580 6255);
FORCEPROP 2 LAST PATH I109
J 0
(3825 6400);
DISPLAY 0.680851 (3825 6400);
DISPLAY INVISIBLE (3825 6400);
FORCEADD OFFPAGE..3
(3625 6300);
FORCEPROP 2 LAST $XR0 80 
J 0
(3839 6300);
DISPLAY 0.638298 (3839 6300);
PAINT MONO (3839 6300);
FORCEPROP 2 LAST CDS_LIB standard
J 0
(3625 6300);
DISPLAY INVISIBLE (3625 6300);
FORCEPROP 1 LAST OFFPAGE TRUE
J 0
(3950 6175);
DISPLAY 0.872340 (3950 6175);
DISPLAY INVISIBLE (3950 6175);
FORCEPROP 1 LAST COMMENT_BODY TRUE
J 0
(3575 6200);
DISPLAY 0.872340 (3575 6200);
PAINT GREEN (3575 6200);
DISPLAY INVISIBLE (3575 6200);
FORCEPROP 2 LAST PATH I110
J 0
(3850 6350);
DISPLAY 0.680851 (3850 6350);
DISPLAY INVISIBLE (3850 6350);
FORCEADD UNIVERSAL_GND..1
R 2
(4250 1075);
FORCEPROP 3 LASTPIN (4250 1125) SIG_NAME GND\g
J 0
(4260 1135);
DISPLAY 0.659574 (4260 1135);
PAINT MONO (4260 1135);
DISPLAY INVISIBLE (4260 1135);
FORCEPROP 2 LAST CDS_LIB pure_quanta_power
J 0
(4250 1075);
DISPLAY INVISIBLE (4250 1075);
FORCEPROP 1 LAST HDL_POWER GND
J 1
(4225 1000);
DISPLAY 0.872340 (4225 1000);
PAINT GREEN (4225 1000);
DISPLAY INVISIBLE (4225 1000);
FORCEPROP 1 LAST PATH I111
J 2
(4175 1075);
DISPLAY 0.872340 (4175 1075);
PAINT AQUA (4175 1075);
DISPLAY INVISIBLE (4175 1075);
FORCEADD Q_CAP..1
(4250 1275);
FORCEPROP 1 LAST LOCATION C63
J 0
(4300 1375);
DISPLAY 0.489362 (4300 1375);
PAINT SKYBLUE (4300 1375);
FORCEPROP 0 LAST $SEC 1
J 0
(4300 1400);
DISPLAY 0.680851 (4300 1400);
PAINT MONO (4300 1400);
DISPLAY INVISIBLE (4300 1400);
FORCEPROP 0 LAST CDS_SEC 1
J 0
(4300 1400);
DISPLAY 1.021277 (4300 1400);
DISPLAY INVISIBLE (4300 1400);
FORCEPROP 1 LASTPIN (4250 1375) $PN 1
J 0
(4260 1355);
DISPLAY 0.489362 (4260 1355);
PAINT MONO (4260 1355);
FORCEPROP 1 LASTPIN (4250 1175) $PN 2
J 0
(4260 1155);
DISPLAY 0.489362 (4260 1155);
PAINT MONO (4260 1155);
FORCEPROP 1 LAST TOLERANCE 5%
J 0
(4300 1225);
DISPLAY 0.489362 (4300 1225);
PAINT SKYBLUE (4300 1225);
FORCEPROP 1 LAST PACK_TYPE C0402
J 0
(4300 1175);
DISPLAY 0.489362 (4300 1175);
PAINT SKYBLUE (4300 1175);
FORCEPROP 1 LAST VOLTAGE 50V
J 0
(4300 1275);
DISPLAY 0.489362 (4300 1275);
PAINT SKYBLUE (4300 1275);
FORCEPROP 1 LAST VALUE 220PF
J 0
(4300 1325);
DISPLAY 0.489362 (4300 1325);
PAINT SKYBLUE (4300 1325);
FORCEPROP 2 LAST CDS_LIB pure_quanta
J 0
(4250 1275);
DISPLAY INVISIBLE (4250 1275);
FORCEPROP 1 LAST MATERIAL C0G
J 0
(4300 1175);
DISPLAY 0.404255 (4300 1175);
PAINT SKYBLUE (4300 1175);
DISPLAY INVISIBLE (4300 1175);
FORCEPROP 1 LAST PART_NUMBER CH12206JB00
J 0
(4300 1125);
DISPLAY 0.404255 (4300 1125);
PAINT SKYBLUE (4300 1125);
DISPLAY INVISIBLE (4300 1125);
FORCEPROP 1 LAST PATH I112
J 0
(4300 1425);
DISPLAY 0.978723 (4300 1425);
PAINT WHITE (4300 1425);
DISPLAY INVISIBLE (4300 1425);
FORCEADD Q_RES..1
R 1
(4450 1225);
FORCEPROP 1 LAST LOCATION R130
J 0
(4500 1350);
DISPLAY 0.489362 (4500 1350);
PAINT SKYBLUE (4500 1350);
FORCEPROP 0 LAST $SEC 1
R 1
J 0
(4500 1400);
DISPLAY 0.680851 (4500 1400);
PAINT MONO (4500 1400);
DISPLAY INVISIBLE (4500 1400);
FORCEPROP 0 LAST CDS_SEC 1
R 1
J 0
(4500 1400);
DISPLAY 1.021277 (4500 1400);
DISPLAY INVISIBLE (4500 1400);
FORCEPROP 1 LASTPIN (4450 1125) $PN 1
R 1
J 0
(4438 1137);
DISPLAY 0.489362 (4438 1137);
PAINT MONO (4438 1137);
FORCEPROP 1 LASTPIN (4450 1325) $PN 2
R 1
J 0
(4438 1287);
DISPLAY 0.489362 (4438 1287);
PAINT MONO (4438 1287);
FORCEPROP 1 LAST MATERIAL EMPTY
J 0
(4500 1100);
DISPLAY 0.489362 (4500 1100);
PAINT RED (4500 1100);
FORCEPROP 1 LAST PACK_TYPE 0402LF
J 0
(4500 1150);
DISPLAY 0.489362 (4500 1150);
PAINT SKYBLUE (4500 1150);
FORCEPROP 1 LAST WATTAGE 1/16W
J 0
(4500 1200);
DISPLAY 0.489362 (4500 1200);
PAINT SKYBLUE (4500 1200);
FORCEPROP 1 LAST VALUE 10K
J 0
(4500 1300);
DISPLAY 0.489362 (4500 1300);
PAINT SKYBLUE (4500 1300);
FORCEPROP 1 LAST TOLERANCE 5%
J 0
(4500 1250);
DISPLAY 0.489362 (4500 1250);
PAINT SKYBLUE (4500 1250);
FORCEPROP 2 LAST CDS_LIB pure_quanta
R 1
J 0
(4450 1225);
DISPLAY INVISIBLE (4450 1225);
FORCEPROP 1 LAST PART_NUMBER CS31002JB08
R 1
J 0
(4350 1175);
DISPLAY 0.638298 (4350 1175);
PAINT SKYBLUE (4350 1175);
DISPLAY INVISIBLE (4350 1175);
FORCEPROP 1 LAST PATH I113
R 1
J 0
(4300 1175);
DISPLAY 0.978723 (4300 1175);
PAINT WHITE (4300 1175);
DISPLAY INVISIBLE (4300 1175);
FORCEADD P1V0..1
(4450 1450);
FORCEPROP 3 LASTPIN (4450 1400) SIG_NAME P5V_AUX\g
J 0
(4460 1410);
DISPLAY 0.659574 (4460 1410);
PAINT MONO (4460 1410);
DISPLAY INVISIBLE (4460 1410);
FORCEPROP 1 LAST HDL_POWER P5V_AUX
J 1
(4450 1500);
DISPLAY 0.489362 (4450 1500);
PAINT GREEN (4450 1500);
FORCEPROP 2 LAST CDS_LIB pure_quanta_power
J 0
(4450 1450);
DISPLAY INVISIBLE (4450 1450);
FORCEPROP 1 LAST PATH I114
J 0
(4500 1475);
DISPLAY 0.872340 (4500 1475);
PAINT AQUA (4500 1475);
DISPLAY INVISIBLE (4500 1475);
FORCEADD Q_RES..1
(4275 2075);
FORCEPROP 1 LAST LOCATION R3243
J 0
(4025 2075);
DISPLAY 0.808511 (4025 2075);
FORCEPROP 0 LAST $SEC 1
J 0
(4225 2175);
DISPLAY 0.680851 (4225 2175);
PAINT MONO (4225 2175);
DISPLAY INVISIBLE (4225 2175);
FORCEPROP 0 LAST CDS_SEC 1
J 0
(4225 2175);
DISPLAY 1.021277 (4225 2175);
DISPLAY INVISIBLE (4225 2175);
FORCEPROP 1 LASTPIN (4175 2075) $PN 1
J 0
(4187 2087);
DISPLAY 0.787234 (4187 2087);
PAINT MONO (4187 2087);
FORCEPROP 1 LASTPIN (4375 2075) $PN 2
J 0
(4337 2087);
DISPLAY 0.787234 (4337 2087);
PAINT MONO (4337 2087);
FORCEPROP 1 LAST TOLERANCE 5%
J 0
(4500 2075);
DISPLAY 0.510638 (4500 2075);
FORCEPROP 1 LAST MATERIAL EMPTY
J 0
(4575 2075);
DISPLAY 0.510638 (4575 2075);
PAINT RED (4575 2075);
FORCEPROP 1 LAST VALUE 2.2K
J 2
(4500 2075);
DISPLAY 0.510638 (4500 2075);
FORCEPROP 2 LAST CDS_LIB pure_quanta
J 0
(4275 2075);
DISPLAY INVISIBLE (4275 2075);
FORCEPROP 1 LAST PACK_TYPE 0402LF
J 0
(4175 2175);
DISPLAY 0.510638 (4175 2175);
DISPLAY INVISIBLE (4175 2175);
FORCEPROP 1 LAST WATTAGE 1/16W
J 2
(4475 2175);
DISPLAY 0.510638 (4475 2175);
DISPLAY INVISIBLE (4475 2175);
FORCEPROP 1 LAST PART_NUMBER CS22202JB07
J 0
(4175 2125);
DISPLAY 0.510638 (4175 2125);
DISPLAY INVISIBLE (4175 2125);
FORCEPROP 1 LAST PATH I115
J 0
(4225 2225);
DISPLAY 0.978723 (4225 2225);
PAINT WHITE (4225 2225);
DISPLAY INVISIBLE (4225 2225);
FORCEADD Q_RES..2
(4675 1200);
FORCEPROP 1 LAST LOCATION R131
J 2
(4750 1300);
DISPLAY 0.489362 (4750 1300);
PAINT SKYBLUE (4750 1300);
FORCEPROP 0 LAST $SEC 1
J 0
(4750 1350);
DISPLAY 0.680851 (4750 1350);
PAINT MONO (4750 1350);
DISPLAY INVISIBLE (4750 1350);
FORCEPROP 0 LAST CDS_SEC 1
J 0
(4750 1350);
DISPLAY 1.021277 (4750 1350);
DISPLAY INVISIBLE (4750 1350);
FORCEPROP 1 LASTPIN (4675 1300) $PN 1
J 0
(4680 1262);
DISPLAY 0.489362 (4680 1262);
PAINT MONO (4680 1262);
FORCEPROP 1 LASTPIN (4675 1100) $PN 2
J 0
(4680 1110);
DISPLAY 0.489362 (4680 1110);
PAINT MONO (4680 1110);
FORCEPROP 1 LAST PACK_TYPE 0402LF
J 0
(4700 1150);
DISPLAY 0.489362 (4700 1150);
PAINT SKYBLUE (4700 1150);
FORCEPROP 1 LAST VALUE 10K
J 0
(4700 1250);
DISPLAY 0.489362 (4700 1250);
PAINT SKYBLUE (4700 1250);
FORCEPROP 1 LAST TOLERANCE 5%
J 0
(4700 1225);
DISPLAY 0.489362 (4700 1225);
PAINT SKYBLUE (4700 1225);
FORCEPROP 1 LAST MATERIAL CHIP
J 0
(4700 1175);
DISPLAY 0.489362 (4700 1175);
PAINT SKYBLUE (4700 1175);
FORCEPROP 1 LAST WATTAGE 1/16W
J 0
(4700 1200);
DISPLAY 0.489362 (4700 1200);
PAINT SKYBLUE (4700 1200);
FORCEPROP 2 LAST CDS_LIB pure_quanta
J 0
(4675 1200);
DISPLAY INVISIBLE (4675 1200);
FORCEPROP 1 LAST PART_NUMBER CS31002JB08
J 2
(4650 1125);
DISPLAY 0.489362 (4650 1125);
PAINT SKYBLUE (4650 1125);
DISPLAY INVISIBLE (4650 1125);
FORCEPROP 1 LAST PATH I116
J 0
(4725 1375);
DISPLAY 0.978723 (4725 1375);
PAINT WHITE (4725 1375);
DISPLAY INVISIBLE (4725 1375);
FORCEADD UNIVERSAL_GND..1
R 2
(4850 1300);
FORCEPROP 3 LASTPIN (4850 1350) SIG_NAME GND\g
J 0
(4860 1360);
DISPLAY 0.659574 (4860 1360);
PAINT MONO (4860 1360);
DISPLAY INVISIBLE (4860 1360);
FORCEPROP 2 LAST CDS_LIB pure_quanta_power
J 2
(4850 1300);
DISPLAY INVISIBLE (4850 1300);
FORCEPROP 1 LAST HDL_POWER GND
J 1
(4825 1225);
DISPLAY 0.872340 (4825 1225);
PAINT GREEN (4825 1225);
DISPLAY INVISIBLE (4825 1225);
FORCEPROP 1 LAST PATH I117
J 2
(4775 1300);
DISPLAY 0.872340 (4775 1300);
PAINT AQUA (4775 1300);
DISPLAY INVISIBLE (4775 1300);
FORCEADD UNIVERSAL_POWER..1
(4675 1450);
FORCEPROP 3 LASTPIN (4675 1400) SIG_NAME P3V3_AUX\g
J 0
(4685 1410);
DISPLAY 0.659574 (4685 1410);
PAINT MONO (4685 1410);
DISPLAY INVISIBLE (4685 1410);
FORCEPROP 1 LAST HDL_POWER P3V3_AUX
J 1
(4675 1500);
DISPLAY 0.489362 (4675 1500);
PAINT GREEN (4675 1500);
FORCEPROP 2 LAST CDS_LIB pure_quanta_power
J 0
(4675 1450);
DISPLAY INVISIBLE (4675 1450);
FORCEPROP 2 LAST BOM_COST VR_SYSTEM 
J 0
(4675 1550);
DISPLAY 0.680851 (4675 1550);
DISPLAY INVISIBLE (4675 1550);
FORCEPROP 1 LAST PATH I118
J 0
(4725 1475);
DISPLAY 0.872340 (4725 1475);
PAINT AQUA (4725 1475);
DISPLAY INVISIBLE (4725 1475);
FORCEADD Q_RES..1
(4275 2125);
FORCEPROP 1 LAST LOCATION R3242
J 0
(4025 2125);
DISPLAY 0.808511 (4025 2125);
FORCEPROP 0 LAST $SEC 1
J 0
(4425 2275);
DISPLAY 0.680851 (4425 2275);
PAINT MONO (4425 2275);
DISPLAY INVISIBLE (4425 2275);
FORCEPROP 0 LAST CDS_SEC 1
J 0
(4425 2275);
DISPLAY 1.021277 (4425 2275);
DISPLAY INVISIBLE (4425 2275);
FORCEPROP 1 LASTPIN (4175 2125) $PN 1
J 0
(4187 2137);
DISPLAY 0.787234 (4187 2137);
PAINT MONO (4187 2137);
FORCEPROP 1 LASTPIN (4375 2125) $PN 2
J 0
(4337 2137);
DISPLAY 0.787234 (4337 2137);
PAINT MONO (4337 2137);
FORCEPROP 1 LAST MATERIAL EMPTY
J 0
(4575 2125);
DISPLAY 0.510638 (4575 2125);
PAINT RED (4575 2125);
FORCEPROP 1 LAST TOLERANCE 5%
J 0
(4500 2125);
DISPLAY 0.510638 (4500 2125);
FORCEPROP 1 LAST VALUE 2.2K
J 2
(4500 2125);
DISPLAY 0.510638 (4500 2125);
FORCEPROP 1 LAST WATTAGE 1/16W
J 2
(4425 2250);
DISPLAY 0.510638 (4425 2250);
FORCEPROP 1 LAST PACK_TYPE 0402LF
J 0
(4125 2250);
DISPLAY 0.510638 (4125 2250);
FORCEPROP 2 LAST CDS_LIB pure_quanta
J 0
(4275 2125);
DISPLAY INVISIBLE (4275 2125);
FORCEPROP 1 LAST PART_NUMBER CS22202JB07
J 0
(4125 2200);
DISPLAY 0.510638 (4125 2200);
DISPLAY INVISIBLE (4125 2200);
FORCEPROP 1 LAST PATH I119
J 0
(4225 2275);
DISPLAY 0.978723 (4225 2275);
PAINT WHITE (4225 2275);
DISPLAY INVISIBLE (4225 2275);
FORCEADD Q_RES..1
(4275 2425);
FORCEPROP 1 LAST LOCATION R3240
J 0
(4025 2425);
DISPLAY 0.808511 (4025 2425);
FORCEPROP 0 LAST $SEC 1
J 0
(4425 2575);
DISPLAY 0.680851 (4425 2575);
PAINT MONO (4425 2575);
DISPLAY INVISIBLE (4425 2575);
FORCEPROP 0 LAST CDS_SEC 1
J 0
(4425 2575);
DISPLAY 1.021277 (4425 2575);
DISPLAY INVISIBLE (4425 2575);
FORCEPROP 1 LASTPIN (4175 2425) $PN 1
J 0
(4187 2437);
DISPLAY 0.787234 (4187 2437);
PAINT MONO (4187 2437);
FORCEPROP 1 LASTPIN (4375 2425) $PN 2
J 0
(4337 2437);
DISPLAY 0.787234 (4337 2437);
PAINT MONO (4337 2437);
FORCEPROP 1 LAST MATERIAL EMPTY
J 0
(4575 2425);
DISPLAY 0.510638 (4575 2425);
PAINT RED (4575 2425);
FORCEPROP 1 LAST VALUE 2.2K
J 2
(4500 2425);
DISPLAY 0.510638 (4500 2425);
FORCEPROP 1 LAST TOLERANCE 5%
J 0
(4500 2425);
DISPLAY 0.510638 (4500 2425);
FORCEPROP 1 LAST WATTAGE 1/16W
J 2
(4425 2550);
DISPLAY 0.510638 (4425 2550);
FORCEPROP 1 LAST PACK_TYPE 0402LF
J 0
(4125 2550);
DISPLAY 0.510638 (4125 2550);
FORCEPROP 2 LAST CDS_LIB pure_quanta
J 0
(4275 2425);
DISPLAY INVISIBLE (4275 2425);
FORCEPROP 1 LAST PART_NUMBER CS22202JB07
J 0
(4125 2500);
DISPLAY 0.510638 (4125 2500);
DISPLAY INVISIBLE (4125 2500);
FORCEPROP 1 LAST PATH I120
J 0
(4225 2575);
DISPLAY 0.978723 (4225 2575);
PAINT WHITE (4225 2575);
DISPLAY INVISIBLE (4225 2575);
FORCEADD Q_RES..1
(4275 2650);
FORCEPROP 1 LAST LOCATION R3227
J 0
(4025 2650);
DISPLAY 0.787234 (4025 2650);
FORCEPROP 0 LAST $SEC 1
J 0
(4025 2700);
DISPLAY 0.680851 (4025 2700);
PAINT MONO (4025 2700);
DISPLAY INVISIBLE (4025 2700);
FORCEPROP 0 LAST CDS_SEC 1
J 0
(4025 2700);
DISPLAY 1.021277 (4025 2700);
DISPLAY INVISIBLE (4025 2700);
FORCEPROP 1 LASTPIN (4175 2650) $PN 1
J 0
(4187 2662);
DISPLAY 0.787234 (4187 2662);
PAINT MONO (4187 2662);
FORCEPROP 1 LASTPIN (4375 2650) $PN 2
J 0
(4337 2662);
DISPLAY 0.787234 (4337 2662);
PAINT MONO (4337 2662);
FORCEPROP 1 LAST MATERIAL EMPTY
J 0
(4575 2650);
DISPLAY 0.510638 (4575 2650);
PAINT RED (4575 2650);
FORCEPROP 1 LAST VALUE 2.2K
J 2
(4500 2650);
DISPLAY 0.510638 (4500 2650);
FORCEPROP 1 LAST TOLERANCE 5%
J 0
(4500 2650);
DISPLAY 0.510638 (4500 2650);
FORCEPROP 2 LAST CDS_LIB pure_quanta
J 0
(4275 2650);
DISPLAY INVISIBLE (4275 2650);
FORCEPROP 1 LAST WATTAGE 1/16W
J 2
(4475 2750);
DISPLAY 0.510638 (4475 2750);
DISPLAY INVISIBLE (4475 2750);
FORCEPROP 1 LAST PACK_TYPE 0402LF
J 0
(4175 2750);
DISPLAY 0.510638 (4175 2750);
DISPLAY INVISIBLE (4175 2750);
FORCEPROP 1 LAST PART_NUMBER CS22202JB07
J 0
(4175 2700);
DISPLAY 0.510638 (4175 2700);
DISPLAY INVISIBLE (4175 2700);
FORCEPROP 1 LAST PATH I121
J 0
(4225 2800);
DISPLAY 0.978723 (4225 2800);
PAINT WHITE (4225 2800);
DISPLAY INVISIBLE (4225 2800);
FORCEADD Q_RES..1
(4275 2700);
FORCEPROP 1 LAST LOCATION R3226
J 0
(4025 2700);
DISPLAY 0.787234 (4025 2700);
FORCEPROP 0 LAST $SEC 1
J 0
(4425 2850);
DISPLAY 0.680851 (4425 2850);
PAINT MONO (4425 2850);
DISPLAY INVISIBLE (4425 2850);
FORCEPROP 0 LAST CDS_SEC 1
J 0
(4425 2850);
DISPLAY 1.021277 (4425 2850);
DISPLAY INVISIBLE (4425 2850);
FORCEPROP 1 LASTPIN (4175 2700) $PN 1
J 0
(4187 2712);
DISPLAY 0.787234 (4187 2712);
PAINT MONO (4187 2712);
FORCEPROP 1 LASTPIN (4375 2700) $PN 2
J 0
(4337 2712);
DISPLAY 0.787234 (4337 2712);
PAINT MONO (4337 2712);
FORCEPROP 1 LAST MATERIAL EMPTY
J 0
(4575 2700);
DISPLAY 0.510638 (4575 2700);
PAINT RED (4575 2700);
FORCEPROP 1 LAST VALUE 2.2K
J 2
(4500 2700);
DISPLAY 0.510638 (4500 2700);
FORCEPROP 1 LAST TOLERANCE 5%
J 0
(4500 2700);
DISPLAY 0.510638 (4500 2700);
FORCEPROP 1 LAST WATTAGE 1/16W
J 2
(4425 2825);
DISPLAY 0.510638 (4425 2825);
FORCEPROP 1 LAST PACK_TYPE 0402LF
J 0
(4125 2825);
DISPLAY 0.510638 (4125 2825);
FORCEPROP 2 LAST CDS_LIB pure_quanta
J 0
(4275 2700);
DISPLAY INVISIBLE (4275 2700);
FORCEPROP 1 LAST PART_NUMBER CS22202JB07
J 0
(4125 2775);
DISPLAY 0.510638 (4125 2775);
DISPLAY INVISIBLE (4125 2775);
FORCEPROP 1 LAST PATH I122
J 0
(4225 2850);
DISPLAY 0.978723 (4225 2850);
PAINT WHITE (4225 2850);
DISPLAY INVISIBLE (4225 2850);
FORCEADD Q_RES..1
(4275 3050);
FORCEPROP 1 LAST LOCATION R3004
J 0
(4025 3050);
DISPLAY 0.787234 (4025 3050);
FORCEPROP 0 LAST $SEC 1
J 0
(4025 3100);
DISPLAY 0.680851 (4025 3100);
PAINT MONO (4025 3100);
DISPLAY INVISIBLE (4025 3100);
FORCEPROP 0 LAST CDS_SEC 1
J 0
(4025 3100);
DISPLAY 1.021277 (4025 3100);
DISPLAY INVISIBLE (4025 3100);
FORCEPROP 1 LASTPIN (4175 3050) $PN 1
J 0
(4187 3062);
DISPLAY 0.787234 (4187 3062);
PAINT MONO (4187 3062);
FORCEPROP 1 LASTPIN (4375 3050) $PN 2
J 0
(4337 3062);
DISPLAY 0.787234 (4337 3062);
PAINT MONO (4337 3062);
FORCEPROP 1 LAST MATERIAL EMPTY
J 0
(4575 3050);
DISPLAY 0.510638 (4575 3050);
PAINT RED (4575 3050);
FORCEPROP 1 LAST TOLERANCE 5%
J 0
(4500 3050);
DISPLAY 0.510638 (4500 3050);
FORCEPROP 1 LAST VALUE 2.2K
J 2
(4500 3050);
DISPLAY 0.510638 (4500 3050);
FORCEPROP 1 LAST PACK_TYPE 0402LF
J 0
(4175 3150);
DISPLAY 0.510638 (4175 3150);
DISPLAY INVISIBLE (4175 3150);
FORCEPROP 1 LAST WATTAGE 1/16W
J 2
(4475 3150);
DISPLAY 0.510638 (4475 3150);
DISPLAY INVISIBLE (4475 3150);
FORCEPROP 2 LAST CDS_LIB pure_quanta
J 0
(4275 3050);
DISPLAY INVISIBLE (4275 3050);
FORCEPROP 1 LAST PART_NUMBER CS22202JB07
J 0
(4175 3100);
DISPLAY 0.510638 (4175 3100);
DISPLAY INVISIBLE (4175 3100);
FORCEPROP 1 LAST PATH I123
J 0
(4225 3200);
DISPLAY 0.978723 (4225 3200);
PAINT WHITE (4225 3200);
DISPLAY INVISIBLE (4225 3200);
FORCEADD Q_RES..1
(4275 3100);
FORCEPROP 1 LAST LOCATION R2999
J 0
(4025 3100);
DISPLAY 0.787234 (4025 3100);
FORCEPROP 0 LAST $SEC 1
J 0
(4425 3250);
DISPLAY 0.680851 (4425 3250);
PAINT MONO (4425 3250);
DISPLAY INVISIBLE (4425 3250);
FORCEPROP 0 LAST CDS_SEC 1
J 0
(4425 3250);
DISPLAY 1.021277 (4425 3250);
DISPLAY INVISIBLE (4425 3250);
FORCEPROP 1 LASTPIN (4175 3100) $PN 1
J 0
(4187 3112);
DISPLAY 0.787234 (4187 3112);
PAINT MONO (4187 3112);
FORCEPROP 1 LASTPIN (4375 3100) $PN 2
J 0
(4337 3112);
DISPLAY 0.787234 (4337 3112);
PAINT MONO (4337 3112);
FORCEPROP 1 LAST MATERIAL EMPTY
J 0
(4575 3100);
DISPLAY 0.510638 (4575 3100);
PAINT RED (4575 3100);
FORCEPROP 1 LAST TOLERANCE 5%
J 0
(4500 3100);
DISPLAY 0.510638 (4500 3100);
FORCEPROP 1 LAST VALUE 2.2K
J 2
(4500 3100);
DISPLAY 0.510638 (4500 3100);
FORCEPROP 1 LAST WATTAGE 1/16W
J 2
(4425 3225);
DISPLAY 0.510638 (4425 3225);
FORCEPROP 1 LAST PACK_TYPE 0402LF
J 0
(4125 3225);
DISPLAY 0.510638 (4125 3225);
FORCEPROP 2 LAST CDS_LIB pure_quanta
J 0
(4275 3100);
DISPLAY INVISIBLE (4275 3100);
FORCEPROP 1 LAST PART_NUMBER CS22202JB07
J 0
(4125 3175);
DISPLAY 0.510638 (4125 3175);
DISPLAY INVISIBLE (4125 3175);
FORCEPROP 1 LAST PATH I124
J 0
(4225 3250);
DISPLAY 0.978723 (4225 3250);
PAINT WHITE (4225 3250);
DISPLAY INVISIBLE (4225 3250);
FORCEADD Q_RES..1
(4275 3425);
FORCEPROP 1 LAST LOCATION R2213
J 0
(4025 3425);
DISPLAY 0.787234 (4025 3425);
FORCEPROP 0 LAST $SEC 1
J 0
(4025 3475);
DISPLAY 0.680851 (4025 3475);
PAINT MONO (4025 3475);
DISPLAY INVISIBLE (4025 3475);
FORCEPROP 0 LAST CDS_SEC 1
J 0
(4025 3475);
DISPLAY 1.021277 (4025 3475);
DISPLAY INVISIBLE (4025 3475);
FORCEPROP 1 LASTPIN (4175 3425) $PN 1
J 0
(4187 3437);
DISPLAY 0.787234 (4187 3437);
PAINT MONO (4187 3437);
FORCEPROP 1 LASTPIN (4375 3425) $PN 2
J 0
(4337 3437);
DISPLAY 0.787234 (4337 3437);
PAINT MONO (4337 3437);
FORCEPROP 1 LAST MATERIAL EMPTY
J 0
(4575 3425);
DISPLAY 0.510638 (4575 3425);
PAINT RED (4575 3425);
FORCEPROP 1 LAST TOLERANCE 5%
J 0
(4500 3425);
DISPLAY 0.510638 (4500 3425);
FORCEPROP 1 LAST VALUE 2.2K
J 2
(4500 3425);
DISPLAY 0.510638 (4500 3425);
FORCEPROP 1 LAST PACK_TYPE 0402LF
J 0
(4175 3525);
DISPLAY 0.510638 (4175 3525);
DISPLAY INVISIBLE (4175 3525);
FORCEPROP 1 LAST WATTAGE 1/16W
J 2
(4475 3525);
DISPLAY 0.510638 (4475 3525);
DISPLAY INVISIBLE (4475 3525);
FORCEPROP 2 LAST CDS_LIB pure_quanta
J 0
(4275 3425);
DISPLAY INVISIBLE (4275 3425);
FORCEPROP 1 LAST PART_NUMBER CS22202JB07
J 0
(4175 3475);
DISPLAY 0.510638 (4175 3475);
DISPLAY INVISIBLE (4175 3475);
FORCEPROP 1 LAST PATH I125
J 0
(4225 3575);
DISPLAY 0.978723 (4225 3575);
PAINT WHITE (4225 3575);
DISPLAY INVISIBLE (4225 3575);
FORCEADD Q_RES..1
(4275 3475);
FORCEPROP 1 LAST LOCATION R2212
J 0
(4025 3475);
DISPLAY 0.787234 (4025 3475);
FORCEPROP 0 LAST $SEC 1
J 0
(4425 3625);
DISPLAY 0.680851 (4425 3625);
PAINT MONO (4425 3625);
DISPLAY INVISIBLE (4425 3625);
FORCEPROP 0 LAST CDS_SEC 1
J 0
(4425 3625);
DISPLAY 1.021277 (4425 3625);
DISPLAY INVISIBLE (4425 3625);
FORCEPROP 1 LASTPIN (4175 3475) $PN 1
J 0
(4187 3487);
DISPLAY 0.787234 (4187 3487);
PAINT MONO (4187 3487);
FORCEPROP 1 LASTPIN (4375 3475) $PN 2
J 0
(4337 3487);
DISPLAY 0.787234 (4337 3487);
PAINT MONO (4337 3487);
FORCEPROP 1 LAST WATTAGE 1/16W
J 2
(4425 3600);
DISPLAY 0.510638 (4425 3600);
FORCEPROP 1 LAST PACK_TYPE 0402LF
J 0
(4125 3600);
DISPLAY 0.510638 (4125 3600);
FORCEPROP 1 LAST MATERIAL EMPTY
J 0
(4575 3475);
DISPLAY 0.510638 (4575 3475);
PAINT RED (4575 3475);
FORCEPROP 1 LAST VALUE 2.2K
J 2
(4500 3475);
DISPLAY 0.510638 (4500 3475);
FORCEPROP 1 LAST TOLERANCE 5%
J 0
(4500 3475);
DISPLAY 0.510638 (4500 3475);
FORCEPROP 2 LAST CDS_LIB pure_quanta
J 0
(4275 3475);
DISPLAY INVISIBLE (4275 3475);
FORCEPROP 1 LAST PART_NUMBER CS22202JB07
J 0
(4125 3550);
DISPLAY 0.510638 (4125 3550);
DISPLAY INVISIBLE (4125 3550);
FORCEPROP 1 LAST PATH I126
J 0
(4225 3625);
DISPLAY 0.978723 (4225 3625);
PAINT WHITE (4225 3625);
DISPLAY INVISIBLE (4225 3625);
FORCEADD Q_RES..1
(4275 3725);
FORCEPROP 1 LAST LOCATION R1460
J 0
(4025 3725);
DISPLAY 0.638298 (4025 3725);
FORCEPROP 2 LAST $SEC 1
J 0
(4225 3925);
DISPLAY 0.680851 (4225 3925);
PAINT MONO (4225 3925);
DISPLAY INVISIBLE (4225 3925);
FORCEPROP 2 LAST CDS_SEC 1
J 0
(4225 3925);
DISPLAY 1.021277 (4225 3925);
DISPLAY INVISIBLE (4225 3925);
FORCEPROP 1 LASTPIN (4175 3725) $PN 1
J 0
(4187 3737);
DISPLAY 0.787234 (4187 3737);
FORCEPROP 1 LASTPIN (4375 3725) $PN 2
J 0
(4337 3737);
DISPLAY 0.787234 (4337 3737);
FORCEPROP 1 LAST MATERIAL EMPTY
J 0
(4575 3725);
DISPLAY 0.510638 (4575 3725);
PAINT RED (4575 3725);
FORCEPROP 1 LAST TOLERANCE 5%
J 0
(4500 3725);
DISPLAY 0.510638 (4500 3725);
FORCEPROP 1 LAST VALUE 2.2K
J 2
(4500 3725);
DISPLAY 0.510638 (4500 3725);
FORCEPROP 1 LAST PACK_TYPE 0402LF
J 0
(4175 3825);
DISPLAY 0.510638 (4175 3825);
DISPLAY INVISIBLE (4175 3825);
FORCEPROP 1 LAST WATTAGE 1/16W
J 2
(4475 3825);
DISPLAY 0.510638 (4475 3825);
DISPLAY INVISIBLE (4475 3825);
FORCEPROP 2 LAST CDS_LIB pure_quanta
J 0
(4275 3725);
PAINT MONO (4275 3725);
DISPLAY INVISIBLE (4275 3725);
FORCEPROP 1 LAST PART_NUMBER CS22202JB07
J 0
(4175 3775);
DISPLAY 0.510638 (4175 3775);
DISPLAY INVISIBLE (4175 3775);
FORCEPROP 1 LAST PATH I127
J 0
(4225 3875);
DISPLAY 0.978723 (4225 3875);
PAINT WHITE (4225 3875);
DISPLAY INVISIBLE (4225 3875);
FORCEADD Q_RES..1
(4275 3775);
FORCEPROP 1 LAST LOCATION R332
J 0
(4025 3775);
DISPLAY 0.638298 (4025 3775);
FORCEPROP 2 LAST $SEC 1
J 0
(4225 3975);
DISPLAY 0.680851 (4225 3975);
PAINT MONO (4225 3975);
DISPLAY INVISIBLE (4225 3975);
FORCEPROP 2 LAST CDS_SEC 1
J 0
(4225 3975);
DISPLAY 1.021277 (4225 3975);
DISPLAY INVISIBLE (4225 3975);
FORCEPROP 1 LASTPIN (4175 3775) $PN 1
J 0
(4187 3787);
DISPLAY 0.787234 (4187 3787);
FORCEPROP 1 LASTPIN (4375 3775) $PN 2
J 0
(4337 3787);
DISPLAY 0.787234 (4337 3787);
FORCEPROP 1 LAST WATTAGE 1/16W
J 2
(4425 3900);
DISPLAY 0.510638 (4425 3900);
FORCEPROP 1 LAST MATERIAL EMPTY
J 0
(4575 3775);
DISPLAY 0.510638 (4575 3775);
PAINT RED (4575 3775);
FORCEPROP 1 LAST TOLERANCE 5%
J 0
(4500 3775);
DISPLAY 0.510638 (4500 3775);
FORCEPROP 1 LAST VALUE 2.2K
J 2
(4500 3775);
DISPLAY 0.510638 (4500 3775);
FORCEPROP 1 LAST PACK_TYPE 0402LF
J 0
(4125 3900);
DISPLAY 0.510638 (4125 3900);
FORCEPROP 2 LAST CDS_LIB pure_quanta
J 0
(4275 3775);
PAINT MONO (4275 3775);
DISPLAY INVISIBLE (4275 3775);
FORCEPROP 1 LAST PART_NUMBER CS22202JB07
J 0
(4125 3850);
DISPLAY 0.510638 (4125 3850);
DISPLAY INVISIBLE (4125 3850);
FORCEPROP 1 LAST PATH I128
J 0
(4225 3925);
DISPLAY 0.978723 (4225 3925);
PAINT WHITE (4225 3925);
DISPLAY INVISIBLE (4225 3925);
FORCEADD Q_RES..1
(4275 4125);
FORCEPROP 1 LAST LOCATION R331
J 0
(4025 4125);
DISPLAY 0.638298 (4025 4125);
FORCEPROP 2 LAST $SEC 1
J 0
(4225 4325);
DISPLAY 0.680851 (4225 4325);
PAINT MONO (4225 4325);
DISPLAY INVISIBLE (4225 4325);
FORCEPROP 2 LAST CDS_SEC 1
J 0
(4225 4325);
DISPLAY 1.021277 (4225 4325);
DISPLAY INVISIBLE (4225 4325);
FORCEPROP 1 LASTPIN (4175 4125) $PN 1
J 0
(4187 4137);
DISPLAY 0.787234 (4187 4137);
FORCEPROP 1 LASTPIN (4375 4125) $PN 2
J 0
(4337 4137);
DISPLAY 0.787234 (4337 4137);
FORCEPROP 1 LAST MATERIAL EMPTY
J 0
(4575 4125);
DISPLAY 0.510638 (4575 4125);
PAINT RED (4575 4125);
FORCEPROP 1 LAST TOLERANCE 5%
J 0
(4500 4125);
DISPLAY 0.510638 (4500 4125);
FORCEPROP 1 LAST VALUE 2.2K
J 2
(4500 4125);
DISPLAY 0.510638 (4500 4125);
FORCEPROP 1 LAST WATTAGE 1/16W
J 2
(4475 4225);
DISPLAY 0.510638 (4475 4225);
DISPLAY INVISIBLE (4475 4225);
FORCEPROP 1 LAST PACK_TYPE 0402LF
J 0
(4175 4225);
DISPLAY 0.510638 (4175 4225);
DISPLAY INVISIBLE (4175 4225);
FORCEPROP 2 LAST CDS_LIB pure_quanta
J 0
(4275 4125);
PAINT MONO (4275 4125);
DISPLAY INVISIBLE (4275 4125);
FORCEPROP 1 LAST PART_NUMBER CS22202JB07
J 0
(4175 4175);
DISPLAY 0.510638 (4175 4175);
DISPLAY INVISIBLE (4175 4175);
FORCEPROP 1 LAST PATH I129
J 0
(4225 4275);
DISPLAY 0.978723 (4225 4275);
PAINT WHITE (4225 4275);
DISPLAY INVISIBLE (4225 4275);
FORCEADD OFFPAGE..3
(-625 2275);
FORCEPROP 2 LAST $XR0 210 
J 0
(-411 2275);
DISPLAY 0.638298 (-411 2275);
PAINT MONO (-411 2275);
FORCEPROP 2 LAST CDS_LIB standard
J 0
(-625 2275);
DISPLAY INVISIBLE (-625 2275);
FORCEPROP 1 LAST OFFPAGE TRUE
J 0
(-300 2150);
DISPLAY 0.872340 (-300 2150);
PAINT GREEN (-300 2150);
DISPLAY INVISIBLE (-300 2150);
FORCEPROP 1 LAST COMMENT_BODY TRUE
J 0
(-675 2175);
DISPLAY 0.872340 (-675 2175);
PAINT GREEN (-675 2175);
DISPLAY INVISIBLE (-675 2175);
FORCEPROP 2 LAST PATH I13
J 0
(-400 2325);
DISPLAY 0.680851 (-400 2325);
DISPLAY INVISIBLE (-400 2325);
FORCEADD Q_RES..1
(4275 4175);
FORCEPROP 1 LAST LOCATION R330
J 0
(4025 4175);
DISPLAY 0.638298 (4025 4175);
FORCEPROP 2 LAST $SEC 1
J 0
(4225 4375);
DISPLAY 0.680851 (4225 4375);
PAINT MONO (4225 4375);
DISPLAY INVISIBLE (4225 4375);
FORCEPROP 2 LAST CDS_SEC 1
J 0
(4225 4375);
DISPLAY 1.021277 (4225 4375);
DISPLAY INVISIBLE (4225 4375);
FORCEPROP 1 LASTPIN (4175 4175) $PN 1
J 0
(4187 4187);
DISPLAY 0.787234 (4187 4187);
FORCEPROP 1 LASTPIN (4375 4175) $PN 2
J 0
(4337 4187);
DISPLAY 0.787234 (4337 4187);
FORCEPROP 1 LAST PACK_TYPE 0402LF
J 0
(4125 4300);
DISPLAY 0.510638 (4125 4300);
FORCEPROP 1 LAST MATERIAL EMPTY
J 0
(4575 4175);
DISPLAY 0.510638 (4575 4175);
PAINT RED (4575 4175);
FORCEPROP 1 LAST TOLERANCE 5%
J 0
(4500 4175);
DISPLAY 0.510638 (4500 4175);
FORCEPROP 1 LAST VALUE 2.2K
J 2
(4500 4175);
DISPLAY 0.510638 (4500 4175);
FORCEPROP 1 LAST WATTAGE 1/16W
J 2
(4425 4300);
DISPLAY 0.510638 (4425 4300);
FORCEPROP 2 LAST CDS_LIB pure_quanta
J 0
(4275 4175);
PAINT MONO (4275 4175);
DISPLAY INVISIBLE (4275 4175);
FORCEPROP 1 LAST PART_NUMBER CS22202JB07
J 0
(4125 4250);
DISPLAY 0.510638 (4125 4250);
DISPLAY INVISIBLE (4125 4250);
FORCEPROP 1 LAST PATH I130
J 0
(4225 4325);
DISPLAY 0.978723 (4225 4325);
PAINT WHITE (4225 4325);
DISPLAY INVISIBLE (4225 4325);
FORCEADD Q_RES..1
(4275 4525);
FORCEPROP 1 LAST LOCATION R6036
J 0
(4000 4525);
DISPLAY 0.638298 (4000 4525);
FORCEPROP 2 LAST $SEC 1
J 0
(4225 4725);
DISPLAY 0.680851 (4225 4725);
PAINT MONO (4225 4725);
DISPLAY INVISIBLE (4225 4725);
FORCEPROP 2 LAST CDS_SEC 1
J 0
(4225 4725);
DISPLAY 1.021277 (4225 4725);
DISPLAY INVISIBLE (4225 4725);
FORCEPROP 1 LASTPIN (4175 4525) $PN 1
J 0
(4187 4537);
DISPLAY 0.787234 (4187 4537);
FORCEPROP 1 LASTPIN (4375 4525) $PN 2
J 0
(4337 4537);
DISPLAY 0.787234 (4337 4537);
FORCEPROP 1 LAST WATTAGE 1/16W
J 2
(4525 4650);
DISPLAY 0.638298 (4525 4650);
FORCEPROP 1 LAST VALUE 2K
J 2
(4500 4525);
DISPLAY 0.638298 (4500 4525);
FORCEPROP 1 LAST TOLERANCE 1%
J 0
(4550 4525);
DISPLAY 0.638298 (4550 4525);
FORCEPROP 1 LAST MATERIAL EMPTY
J 0
(4650 4525);
DISPLAY 0.638298 (4650 4525);
PAINT RED (4650 4525);
FORCEPROP 1 LAST PACK_TYPE 0402LF
J 0
(4150 4650);
DISPLAY 0.638298 (4150 4650);
FORCEPROP 2 LAST CDS_LIB pure_quanta
J 0
(4275 4525);
PAINT MONO (4275 4525);
DISPLAY INVISIBLE (4275 4525);
FORCEPROP 1 LAST PART_NUMBER CS22002FB07
J 0
(4150 4600);
DISPLAY 0.638298 (4150 4600);
DISPLAY INVISIBLE (4150 4600);
FORCEPROP 1 LAST PATH I131
J 0
(4225 4675);
DISPLAY 0.978723 (4225 4675);
PAINT WHITE (4225 4675);
DISPLAY INVISIBLE (4225 4675);
FORCEADD Q_RES..1
(4275 4475);
FORCEPROP 1 LAST LOCATION R6037
J 0
(4000 4475);
DISPLAY 0.638298 (4000 4475);
FORCEPROP 2 LAST $SEC 1
J 0
(4225 4675);
DISPLAY 0.680851 (4225 4675);
PAINT MONO (4225 4675);
DISPLAY INVISIBLE (4225 4675);
FORCEPROP 2 LAST CDS_SEC 1
J 0
(4225 4675);
DISPLAY 1.021277 (4225 4675);
DISPLAY INVISIBLE (4225 4675);
FORCEPROP 1 LASTPIN (4175 4475) $PN 1
J 0
(4187 4487);
DISPLAY 0.787234 (4187 4487);
FORCEPROP 1 LASTPIN (4375 4475) $PN 2
J 0
(4337 4487);
DISPLAY 0.787234 (4337 4487);
FORCEPROP 1 LAST PACK_TYPE 0402LF
J 0
(4150 4600);
DISPLAY 0.638298 (4150 4600);
FORCEPROP 1 LAST TOLERANCE 1%
J 0
(4550 4475);
DISPLAY 0.638298 (4550 4475);
FORCEPROP 1 LAST MATERIAL EMPTY
J 0
(4650 4475);
DISPLAY 0.638298 (4650 4475);
PAINT RED (4650 4475);
FORCEPROP 1 LAST VALUE 2K
J 2
(4500 4475);
DISPLAY 0.638298 (4500 4475);
FORCEPROP 1 LAST WATTAGE 1/16W
J 2
(4525 4600);
DISPLAY 0.638298 (4525 4600);
FORCEPROP 2 LAST CDS_LIB pure_quanta
J 0
(4275 4475);
PAINT MONO (4275 4475);
DISPLAY INVISIBLE (4275 4475);
FORCEPROP 1 LAST PART_NUMBER CS22002FB07
J 0
(4150 4550);
DISPLAY 0.638298 (4150 4550);
DISPLAY INVISIBLE (4150 4550);
FORCEPROP 1 LAST PATH I132
J 0
(4225 4625);
DISPLAY 0.978723 (4225 4625);
PAINT WHITE (4225 4625);
DISPLAY INVISIBLE (4225 4625);
FORCEADD Q_RES..1
(4275 4725);
FORCEPROP 1 LAST LOCATION R329
J 0
(4000 4725);
DISPLAY 0.638298 (4000 4725);
FORCEPROP 2 LAST $SEC 1
J 0
(4225 4925);
DISPLAY 0.680851 (4225 4925);
PAINT MONO (4225 4925);
DISPLAY INVISIBLE (4225 4925);
FORCEPROP 2 LAST CDS_SEC 1
J 0
(4225 4925);
DISPLAY 1.021277 (4225 4925);
DISPLAY INVISIBLE (4225 4925);
FORCEPROP 1 LASTPIN (4175 4725) $PN 1
J 0
(4187 4737);
DISPLAY 0.787234 (4187 4737);
FORCEPROP 1 LASTPIN (4375 4725) $PN 2
J 0
(4337 4737);
DISPLAY 0.787234 (4337 4737);
FORCEPROP 1 LAST TOLERANCE 1%
J 0
(4550 4725);
DISPLAY 0.638298 (4550 4725);
FORCEPROP 1 LAST MATERIAL EMPTY
J 0
(4650 4725);
DISPLAY 0.638298 (4650 4725);
PAINT RED (4650 4725);
FORCEPROP 1 LAST VALUE 2K
J 2
(4500 4725);
DISPLAY 0.638298 (4500 4725);
FORCEPROP 1 LAST PACK_TYPE 0402LF
J 0
(4150 4825);
DISPLAY 0.638298 (4150 4825);
DISPLAY INVISIBLE (4150 4825);
FORCEPROP 1 LAST WATTAGE 1/16W
J 2
(4575 4825);
DISPLAY 0.638298 (4575 4825);
DISPLAY INVISIBLE (4575 4825);
FORCEPROP 2 LAST CDS_LIB pure_quanta
J 0
(4275 4725);
PAINT MONO (4275 4725);
DISPLAY INVISIBLE (4275 4725);
FORCEPROP 1 LAST PART_NUMBER CS22002FB07
J 0
(4150 4775);
DISPLAY 0.638298 (4150 4775);
DISPLAY INVISIBLE (4150 4775);
FORCEPROP 1 LAST PATH I133
J 0
(4225 4875);
DISPLAY 0.978723 (4225 4875);
PAINT WHITE (4225 4875);
DISPLAY INVISIBLE (4225 4875);
FORCEADD Q_RES..1
(4275 4775);
FORCEPROP 1 LAST LOCATION R1386
J 0
(4000 4775);
DISPLAY 0.638298 (4000 4775);
FORCEPROP 2 LAST $SEC 1
J 0
(4225 4975);
DISPLAY 0.680851 (4225 4975);
PAINT MONO (4225 4975);
DISPLAY INVISIBLE (4225 4975);
FORCEPROP 2 LAST CDS_SEC 1
J 0
(4225 4975);
DISPLAY 1.021277 (4225 4975);
DISPLAY INVISIBLE (4225 4975);
FORCEPROP 1 LASTPIN (4175 4775) $PN 1
J 0
(4187 4787);
DISPLAY 0.787234 (4187 4787);
FORCEPROP 1 LASTPIN (4375 4775) $PN 2
J 0
(4337 4787);
DISPLAY 0.787234 (4337 4787);
FORCEPROP 1 LAST VALUE 2K
J 2
(4500 4775);
DISPLAY 0.638298 (4500 4775);
FORCEPROP 1 LAST PACK_TYPE 0402LF
J 0
(4150 4900);
DISPLAY 0.638298 (4150 4900);
FORCEPROP 1 LAST WATTAGE 1/16W
J 2
(4525 4900);
DISPLAY 0.638298 (4525 4900);
FORCEPROP 1 LAST TOLERANCE 1%
J 0
(4550 4775);
DISPLAY 0.638298 (4550 4775);
FORCEPROP 1 LAST MATERIAL EMPTY
J 0
(4650 4775);
DISPLAY 0.638298 (4650 4775);
PAINT RED (4650 4775);
FORCEPROP 2 LAST CDS_LIB pure_quanta
J 0
(4275 4775);
PAINT MONO (4275 4775);
DISPLAY INVISIBLE (4275 4775);
FORCEPROP 1 LAST PART_NUMBER CS22002FB07
J 0
(4150 4850);
DISPLAY 0.638298 (4150 4850);
DISPLAY INVISIBLE (4150 4850);
FORCEPROP 1 LAST PATH I134
J 0
(4225 4925);
DISPLAY 0.978723 (4225 4925);
PAINT WHITE (4225 4925);
DISPLAY INVISIBLE (4225 4925);
FORCEADD Q_RES..1
(4275 4975);
FORCEPROP 1 LAST LOCATION R1385
J 0
(4000 4975);
DISPLAY 0.638298 (4000 4975);
FORCEPROP 2 LAST $SEC 1
J 0
(4225 5175);
DISPLAY 0.680851 (4225 5175);
PAINT MONO (4225 5175);
DISPLAY INVISIBLE (4225 5175);
FORCEPROP 2 LAST CDS_SEC 1
J 0
(4225 5175);
DISPLAY 1.021277 (4225 5175);
DISPLAY INVISIBLE (4225 5175);
FORCEPROP 1 LASTPIN (4175 4975) $PN 1
J 0
(4187 4987);
DISPLAY 0.787234 (4187 4987);
FORCEPROP 1 LASTPIN (4375 4975) $PN 2
J 0
(4337 4987);
DISPLAY 0.787234 (4337 4987);
FORCEPROP 1 LAST MATERIAL EMPTY
J 0
(4650 4975);
DISPLAY 0.638298 (4650 4975);
PAINT RED (4650 4975);
FORCEPROP 1 LAST VALUE 2K
J 2
(4500 4975);
DISPLAY 0.638298 (4500 4975);
FORCEPROP 1 LAST TOLERANCE 1%
J 0
(4550 4975);
DISPLAY 0.638298 (4550 4975);
FORCEPROP 2 LAST CDS_LIB pure_quanta
J 0
(4275 4975);
PAINT MONO (4275 4975);
DISPLAY INVISIBLE (4275 4975);
FORCEPROP 1 LAST WATTAGE 1/16W
J 2
(4575 5075);
DISPLAY 0.638298 (4575 5075);
DISPLAY INVISIBLE (4575 5075);
FORCEPROP 1 LAST PACK_TYPE 0402LF
J 0
(4150 5075);
DISPLAY 0.638298 (4150 5075);
DISPLAY INVISIBLE (4150 5075);
FORCEPROP 1 LAST PART_NUMBER CS22002FB07
J 0
(4150 5025);
DISPLAY 0.638298 (4150 5025);
DISPLAY INVISIBLE (4150 5025);
FORCEPROP 1 LAST PATH I135
J 0
(4225 5125);
DISPLAY 0.978723 (4225 5125);
PAINT WHITE (4225 5125);
DISPLAY INVISIBLE (4225 5125);
FORCEADD Q_RES..1
(4275 5025);
FORCEPROP 1 LAST LOCATION R1384
J 0
(4000 5025);
DISPLAY 0.638298 (4000 5025);
FORCEPROP 2 LAST $SEC 1
J 0
(4225 5225);
DISPLAY 0.680851 (4225 5225);
PAINT MONO (4225 5225);
DISPLAY INVISIBLE (4225 5225);
FORCEPROP 2 LAST CDS_SEC 1
J 0
(4225 5225);
DISPLAY 1.021277 (4225 5225);
DISPLAY INVISIBLE (4225 5225);
FORCEPROP 1 LASTPIN (4175 5025) $PN 1
J 0
(4187 5037);
DISPLAY 0.787234 (4187 5037);
FORCEPROP 1 LASTPIN (4375 5025) $PN 2
J 0
(4337 5037);
DISPLAY 0.787234 (4337 5037);
FORCEPROP 1 LAST TOLERANCE 1%
J 0
(4550 5025);
DISPLAY 0.638298 (4550 5025);
FORCEPROP 1 LAST MATERIAL EMPTY
J 0
(4650 5025);
DISPLAY 0.638298 (4650 5025);
PAINT RED (4650 5025);
FORCEPROP 1 LAST WATTAGE 1/16W
J 2
(4525 5150);
DISPLAY 0.638298 (4525 5150);
FORCEPROP 1 LAST VALUE 2K
J 2
(4500 5025);
DISPLAY 0.638298 (4500 5025);
FORCEPROP 1 LAST PACK_TYPE 0402LF
J 0
(4150 5150);
DISPLAY 0.638298 (4150 5150);
FORCEPROP 2 LAST CDS_LIB pure_quanta
J 0
(4275 5025);
PAINT MONO (4275 5025);
DISPLAY INVISIBLE (4275 5025);
FORCEPROP 1 LAST PART_NUMBER CS22002FB07
J 0
(4150 5100);
DISPLAY 0.638298 (4150 5100);
DISPLAY INVISIBLE (4150 5100);
FORCEPROP 1 LAST PATH I136
J 0
(4225 5175);
DISPLAY 0.978723 (4225 5175);
PAINT WHITE (4225 5175);
DISPLAY INVISIBLE (4225 5175);
FORCEADD Q_RES..1
(4275 5225);
FORCEPROP 1 LAST LOCATION R3062
J 0
(4000 5225);
DISPLAY 0.638298 (4000 5225);
FORCEPROP 2 LAST $SEC 1
J 0
(4225 5425);
DISPLAY 0.680851 (4225 5425);
PAINT MONO (4225 5425);
DISPLAY INVISIBLE (4225 5425);
FORCEPROP 2 LAST CDS_SEC 1
J 0
(4225 5425);
DISPLAY 1.021277 (4225 5425);
DISPLAY INVISIBLE (4225 5425);
FORCEPROP 1 LASTPIN (4175 5225) $PN 1
J 0
(4187 5237);
DISPLAY 0.787234 (4187 5237);
FORCEPROP 1 LASTPIN (4375 5225) $PN 2
J 0
(4337 5237);
DISPLAY 0.787234 (4337 5237);
FORCEPROP 1 LAST TOLERANCE 1%
J 0
(4550 5225);
DISPLAY 0.638298 (4550 5225);
FORCEPROP 1 LAST VALUE 2K
J 2
(4500 5225);
DISPLAY 0.638298 (4500 5225);
FORCEPROP 1 LAST MATERIAL EMPTY
J 0
(4650 5225);
DISPLAY 0.638298 (4650 5225);
PAINT RED (4650 5225);
FORCEPROP 1 LAST PACK_TYPE 0402LF
J 0
(4150 5325);
DISPLAY 0.638298 (4150 5325);
DISPLAY INVISIBLE (4150 5325);
FORCEPROP 1 LAST WATTAGE 1/16W
J 2
(4575 5325);
DISPLAY 0.638298 (4575 5325);
DISPLAY INVISIBLE (4575 5325);
FORCEPROP 2 LAST CDS_LIB pure_quanta
J 0
(4275 5225);
PAINT MONO (4275 5225);
DISPLAY INVISIBLE (4275 5225);
FORCEPROP 1 LAST PART_NUMBER CS22002FB07
J 0
(4150 5275);
DISPLAY 0.638298 (4150 5275);
DISPLAY INVISIBLE (4150 5275);
FORCEPROP 1 LAST PATH I137
J 0
(4225 5375);
DISPLAY 0.978723 (4225 5375);
PAINT WHITE (4225 5375);
DISPLAY INVISIBLE (4225 5375);
FORCEADD Q_RES..1
(4275 5275);
FORCEPROP 1 LAST LOCATION R1319
J 0
(4000 5275);
DISPLAY 0.638298 (4000 5275);
FORCEPROP 2 LAST $SEC 1
J 0
(4225 5475);
DISPLAY 0.680851 (4225 5475);
PAINT MONO (4225 5475);
DISPLAY INVISIBLE (4225 5475);
FORCEPROP 2 LAST CDS_SEC 1
J 0
(4225 5475);
DISPLAY 1.021277 (4225 5475);
DISPLAY INVISIBLE (4225 5475);
FORCEPROP 1 LASTPIN (4175 5275) $PN 1
J 0
(4187 5287);
DISPLAY 0.787234 (4187 5287);
FORCEPROP 1 LASTPIN (4375 5275) $PN 2
J 0
(4337 5287);
DISPLAY 0.787234 (4337 5287);
FORCEPROP 1 LAST VALUE 2K
J 2
(4500 5275);
DISPLAY 0.638298 (4500 5275);
FORCEPROP 1 LAST PACK_TYPE 0402LF
J 0
(4150 5400);
DISPLAY 0.638298 (4150 5400);
FORCEPROP 1 LAST WATTAGE 1/16W
J 2
(4525 5400);
DISPLAY 0.638298 (4525 5400);
FORCEPROP 1 LAST TOLERANCE 1%
J 0
(4550 5275);
DISPLAY 0.638298 (4550 5275);
FORCEPROP 1 LAST MATERIAL EMPTY
J 0
(4650 5275);
DISPLAY 0.638298 (4650 5275);
PAINT RED (4650 5275);
FORCEPROP 2 LAST CDS_LIB pure_quanta
J 0
(4275 5275);
PAINT MONO (4275 5275);
DISPLAY INVISIBLE (4275 5275);
FORCEPROP 1 LAST PART_NUMBER CS22002FB07
J 0
(4150 5350);
DISPLAY 0.638298 (4150 5350);
DISPLAY INVISIBLE (4150 5350);
FORCEPROP 1 LAST PATH I138
J 0
(4225 5425);
DISPLAY 0.978723 (4225 5425);
PAINT WHITE (4225 5425);
DISPLAY INVISIBLE (4225 5425);
FORCEADD UNIVERSAL_POWER..1
(4825 5800);
FORCEPROP 3 LASTPIN (4825 5750) SIG_NAME P3V3_AUX\g
J 0
(4835 5760);
DISPLAY 0.659574 (4835 5760);
PAINT MONO (4835 5760);
DISPLAY INVISIBLE (4835 5760);
FORCEPROP 1 LAST HDL_POWER P3V3_AUX
J 1
(4825 5850);
DISPLAY 0.702128 (4825 5850);
PAINT GREEN (4825 5850);
FORCEPROP 2 LAST CDS_LIB pure_quanta_power
J 0
(4825 5800);
PAINT MONO (4825 5800);
DISPLAY INVISIBLE (4825 5800);
FORCEPROP 1 LAST PATH I139
J 0
(4875 5825);
DISPLAY 0.872340 (4875 5825);
PAINT AQUA (4875 5825);
DISPLAY INVISIBLE (4875 5825);
FORCEADD OFFPAGE..2
(-600 2375);
FORCEPROP 2 LAST $XR0 210 
J 0
(-411 2375);
DISPLAY 0.638298 (-411 2375);
PAINT MONO (-411 2375);
FORCEPROP 2 LAST CDS_LIB standard
J 0
(-600 2375);
DISPLAY INVISIBLE (-600 2375);
FORCEPROP 1 LAST OFFPAGE TRUE
J 0
(-275 2250);
DISPLAY 0.872340 (-275 2250);
PAINT GREEN (-275 2250);
DISPLAY INVISIBLE (-275 2250);
FORCEPROP 1 LAST COMMENT_BODY TRUE
J 0
(-645 2280);
DISPLAY 0.872340 (-645 2280);
PAINT GREEN (-645 2280);
DISPLAY INVISIBLE (-645 2280);
FORCEPROP 2 LAST PATH I14
J 0
(-400 2425);
DISPLAY 0.680851 (-400 2425);
DISPLAY INVISIBLE (-400 2425);
FORCEADD OFFPAGE..3
R 2
(4875 6150);
FORCEPROP 2 LAST $XR0 80 
J 0
(4596 6150);
DISPLAY 0.638298 (4596 6150);
PAINT MONO (4596 6150);
FORCEPROP 2 LAST CDS_LIB standard
J 0
(4875 6150);
DISPLAY INVISIBLE (4875 6150);
FORCEPROP 1 LAST OFFPAGE TRUE
J 2
(4550 6025);
DISPLAY 0.872340 (4550 6025);
PAINT GREEN (4550 6025);
DISPLAY INVISIBLE (4550 6025);
FORCEPROP 1 LAST COMMENT_BODY TRUE
J 2
(4925 6050);
DISPLAY 0.872340 (4925 6050);
PAINT GREEN (4925 6050);
DISPLAY INVISIBLE (4925 6050);
FORCEPROP 2 LAST PATH I140
J 0
(4600 6200);
DISPLAY 0.680851 (4600 6200);
DISPLAY INVISIBLE (4600 6200);
FORCEADD OFFPAGE..3
R 2
(4875 6200);
FORCEPROP 2 LAST $XR0 80 
J 0
(4596 6200);
DISPLAY 0.638298 (4596 6200);
PAINT MONO (4596 6200);
FORCEPROP 2 LAST CDS_LIB standard
J 2
(4875 6200);
DISPLAY INVISIBLE (4875 6200);
FORCEPROP 1 LAST OFFPAGE TRUE
J 2
(4550 6075);
DISPLAY 0.872340 (4550 6075);
PAINT GREEN (4550 6075);
DISPLAY INVISIBLE (4550 6075);
FORCEPROP 1 LAST COMMENT_BODY TRUE
J 2
(4925 6100);
DISPLAY 0.872340 (4925 6100);
PAINT GREEN (4925 6100);
DISPLAY INVISIBLE (4925 6100);
FORCEPROP 2 LAST PATH I141
J 0
(4600 6250);
DISPLAY 0.680851 (4600 6250);
DISPLAY INVISIBLE (4600 6250);
FORCEADD Q_RES..2
(5500 5875);
FORCEPROP 1 LAST LOCATION R889
J 0
(5545 6000);
DISPLAY 0.489362 (5545 6000);
PAINT SKYBLUE (5545 6000);
FORCEPROP 0 LAST $SEC 1
J 0
(5550 6050);
DISPLAY 0.680851 (5550 6050);
PAINT MONO (5550 6050);
DISPLAY INVISIBLE (5550 6050);
FORCEPROP 0 LAST CDS_SEC 1
J 0
(5550 6050);
DISPLAY 1.021277 (5550 6050);
DISPLAY INVISIBLE (5550 6050);
FORCEPROP 1 LASTPIN (5500 5975) $PN 1
J 0
(5505 5937);
DISPLAY 0.489362 (5505 5937);
PAINT MONO (5505 5937);
FORCEPROP 1 LASTPIN (5500 5775) $PN 2
J 0
(5505 5785);
DISPLAY 0.489362 (5505 5785);
PAINT MONO (5505 5785);
FORCEPROP 1 LAST VALUE 10K
J 0
(5545 5975);
DISPLAY 0.489362 (5545 5975);
PAINT SKYBLUE (5545 5975);
FORCEPROP 1 LAST PACK_TYPE 0402LF
J 0
(5540 5775);
DISPLAY 0.489362 (5540 5775);
PAINT SKYBLUE (5540 5775);
FORCEPROP 1 LAST WATTAGE 1/16W
J 0
(5540 5875);
DISPLAY 0.489362 (5540 5875);
PAINT SKYBLUE (5540 5875);
FORCEPROP 1 LAST MATERIAL EMPTY
J 0
(5540 5825);
DISPLAY 0.489362 (5540 5825);
PAINT RED (5540 5825);
FORCEPROP 1 LAST TOLERANCE 5%
J 0
(5545 5925);
DISPLAY 0.489362 (5545 5925);
PAINT SKYBLUE (5545 5925);
FORCEPROP 2 LAST CDS_LIB pure_quanta
J 0
(5500 5875);
DISPLAY INVISIBLE (5500 5875);
FORCEPROP 1 LAST PART_NUMBER CS31002JB08
J 0
(5550 5725);
DISPLAY 0.510638 (5550 5725);
PAINT SKYBLUE (5550 5725);
DISPLAY INVISIBLE (5550 5725);
FORCEPROP 1 LAST PATH I142
J 0
(5550 6050);
DISPLAY 0.978723 (5550 6050);
PAINT WHITE (5550 6050);
DISPLAY INVISIBLE (5550 6050);
FORCEADD GND..1
(5700 5525);
FORCEPROP 3 LASTPIN (5700 5575) SIG_NAME GND\g
J 0
(5710 5585);
DISPLAY 0.659574 (5710 5585);
PAINT MONO (5710 5585);
DISPLAY INVISIBLE (5710 5585);
FORCEPROP 2 LAST BOM_COST MEM
J 0
(5600 5600);
DISPLAY 0.808511 (5600 5600);
DISPLAY INVISIBLE (5600 5600);
FORCEPROP 1 LAST SIZE 1B
J 0
(5775 5475);
DISPLAY 0.851064 (5775 5475);
PAINT GREEN (5775 5475);
DISPLAY INVISIBLE (5775 5475);
FORCEPROP 2 LAST CDS_LIB pure_quanta_power
J 0
(5700 5525);
DISPLAY INVISIBLE (5700 5525);
FORCEPROP 1 LAST HDL_POWER GND
J 0
(5700 5675);
DISPLAY 0.851064 (5700 5675);
PAINT GREEN (5700 5675);
DISPLAY INVISIBLE (5700 5675);
FORCEPROP 1 LAST PATH I143
J 0
(5775 5525);
DISPLAY 0.872340 (5775 5525);
PAINT AQUA (5775 5525);
DISPLAY INVISIBLE (5775 5525);
FORCEADD Q_RES..2
(5700 5875);
FORCEPROP 1 LAST LOCATION R891
J 0
(5745 6000);
DISPLAY 0.489362 (5745 6000);
PAINT SKYBLUE (5745 6000);
FORCEPROP 0 LAST $SEC 1
J 0
(5750 6050);
DISPLAY 0.680851 (5750 6050);
PAINT MONO (5750 6050);
DISPLAY INVISIBLE (5750 6050);
FORCEPROP 0 LAST CDS_SEC 1
J 0
(5750 6050);
DISPLAY 1.021277 (5750 6050);
DISPLAY INVISIBLE (5750 6050);
FORCEPROP 1 LASTPIN (5700 5975) $PN 1
J 0
(5705 5937);
DISPLAY 0.489362 (5705 5937);
PAINT MONO (5705 5937);
FORCEPROP 1 LASTPIN (5700 5775) $PN 2
J 0
(5705 5785);
DISPLAY 0.489362 (5705 5785);
PAINT MONO (5705 5785);
FORCEPROP 1 LAST PACK_TYPE 0402LF
J 0
(5740 5775);
DISPLAY 0.489362 (5740 5775);
PAINT SKYBLUE (5740 5775);
FORCEPROP 1 LAST VALUE 10K
J 0
(5745 5975);
DISPLAY 0.489362 (5745 5975);
PAINT SKYBLUE (5745 5975);
FORCEPROP 1 LAST TOLERANCE 5%
J 0
(5745 5925);
DISPLAY 0.489362 (5745 5925);
PAINT SKYBLUE (5745 5925);
FORCEPROP 1 LAST MATERIAL EMPTY
J 0
(5740 5825);
DISPLAY 0.489362 (5740 5825);
PAINT RED (5740 5825);
FORCEPROP 1 LAST WATTAGE 1/16W
J 0
(5740 5875);
DISPLAY 0.489362 (5740 5875);
PAINT SKYBLUE (5740 5875);
FORCEPROP 2 LAST CDS_LIB pure_quanta
J 0
(5700 5875);
DISPLAY INVISIBLE (5700 5875);
FORCEPROP 1 LAST PART_NUMBER CS31002JB08
J 0
(5750 5725);
DISPLAY 0.510638 (5750 5725);
PAINT SKYBLUE (5750 5725);
DISPLAY INVISIBLE (5750 5725);
FORCEPROP 1 LAST PATH I144
J 0
(5750 6050);
DISPLAY 0.978723 (5750 6050);
PAINT WHITE (5750 6050);
DISPLAY INVISIBLE (5750 6050);
FORCEADD Q_RES..2
(5500 6350);
FORCEPROP 1 LAST LOCATION R888
J 0
(5545 6475);
DISPLAY 0.489362 (5545 6475);
PAINT SKYBLUE (5545 6475);
FORCEPROP 0 LAST $SEC 1
J 0
(5550 6525);
DISPLAY 0.680851 (5550 6525);
PAINT MONO (5550 6525);
DISPLAY INVISIBLE (5550 6525);
FORCEPROP 0 LAST CDS_SEC 1
J 0
(5550 6525);
DISPLAY 1.021277 (5550 6525);
DISPLAY INVISIBLE (5550 6525);
FORCEPROP 1 LASTPIN (5500 6450) $PN 1
J 0
(5505 6412);
DISPLAY 0.489362 (5505 6412);
PAINT MONO (5505 6412);
FORCEPROP 1 LASTPIN (5500 6250) $PN 2
J 0
(5505 6260);
DISPLAY 0.489362 (5505 6260);
PAINT MONO (5505 6260);
FORCEPROP 1 LAST PACK_TYPE 0402LF
J 0
(5540 6250);
DISPLAY 0.489362 (5540 6250);
PAINT SKYBLUE (5540 6250);
FORCEPROP 1 LAST MATERIAL EMPTY
J 0
(5540 6300);
DISPLAY 0.489362 (5540 6300);
PAINT RED (5540 6300);
FORCEPROP 1 LAST WATTAGE 1/16W
J 0
(5540 6350);
DISPLAY 0.489362 (5540 6350);
PAINT SKYBLUE (5540 6350);
FORCEPROP 1 LAST TOLERANCE 5%
J 0
(5545 6400);
DISPLAY 0.489362 (5545 6400);
PAINT SKYBLUE (5545 6400);
FORCEPROP 1 LAST VALUE 10K
J 0
(5545 6450);
DISPLAY 0.489362 (5545 6450);
PAINT SKYBLUE (5545 6450);
FORCEPROP 2 LAST CDS_LIB pure_quanta
J 0
(5500 6350);
DISPLAY INVISIBLE (5500 6350);
FORCEPROP 1 LAST PART_NUMBER CS31002JB08
J 0
(5550 6200);
DISPLAY 0.510638 (5550 6200);
PAINT SKYBLUE (5550 6200);
DISPLAY INVISIBLE (5550 6200);
FORCEPROP 1 LAST PATH I145
J 0
(5550 6525);
DISPLAY 0.978723 (5550 6525);
PAINT WHITE (5550 6525);
DISPLAY INVISIBLE (5550 6525);
FORCEADD VCC_CORE..1
(5500 6625);
FORCEPROP 3 LASTPIN (5500 6575) SIG_NAME P3V3_AUX\g
J 0
(5510 6585);
DISPLAY 0.659574 (5510 6585);
PAINT MONO (5510 6585);
DISPLAY INVISIBLE (5510 6585);
FORCEPROP 1 LAST HDL_POWER P3V3_AUX
J 1
(5500 6675);
DISPLAY 0.489362 (5500 6675);
PAINT GREEN (5500 6675);
FORCEPROP 2 LAST CDS_LIB pure_quanta_power
J 0
(5500 6625);
DISPLAY INVISIBLE (5500 6625);
FORCEPROP 1 LAST PATH I146
J 0
(5550 6650);
DISPLAY 0.872340 (5550 6650);
PAINT AQUA (5550 6650);
DISPLAY INVISIBLE (5550 6650);
FORCEADD Q_RES..2
(5700 6350);
FORCEPROP 1 LAST LOCATION R890
J 0
(5745 6475);
DISPLAY 0.489362 (5745 6475);
PAINT SKYBLUE (5745 6475);
FORCEPROP 0 LAST $SEC 1
J 0
(5750 6525);
DISPLAY 0.680851 (5750 6525);
PAINT MONO (5750 6525);
DISPLAY INVISIBLE (5750 6525);
FORCEPROP 0 LAST CDS_SEC 1
J 0
(5750 6525);
DISPLAY 1.021277 (5750 6525);
DISPLAY INVISIBLE (5750 6525);
FORCEPROP 1 LASTPIN (5700 6450) $PN 1
J 0
(5705 6412);
DISPLAY 0.489362 (5705 6412);
PAINT MONO (5705 6412);
FORCEPROP 1 LASTPIN (5700 6250) $PN 2
J 0
(5705 6260);
DISPLAY 0.489362 (5705 6260);
PAINT MONO (5705 6260);
FORCEPROP 1 LAST PACK_TYPE 0402LF
J 0
(5740 6250);
DISPLAY 0.489362 (5740 6250);
PAINT SKYBLUE (5740 6250);
FORCEPROP 1 LAST MATERIAL EMPTY
J 0
(5740 6300);
DISPLAY 0.489362 (5740 6300);
PAINT RED (5740 6300);
FORCEPROP 1 LAST WATTAGE 1/16W
J 0
(5740 6350);
DISPLAY 0.489362 (5740 6350);
PAINT SKYBLUE (5740 6350);
FORCEPROP 1 LAST TOLERANCE 5%
J 0
(5745 6400);
DISPLAY 0.489362 (5745 6400);
PAINT SKYBLUE (5745 6400);
FORCEPROP 1 LAST VALUE 10K
J 0
(5745 6450);
DISPLAY 0.489362 (5745 6450);
PAINT SKYBLUE (5745 6450);
FORCEPROP 2 LAST CDS_LIB pure_quanta
J 0
(5700 6350);
DISPLAY INVISIBLE (5700 6350);
FORCEPROP 1 LAST PART_NUMBER CS31002JB08
J 0
(5750 6200);
DISPLAY 0.510638 (5750 6200);
PAINT SKYBLUE (5750 6200);
DISPLAY INVISIBLE (5750 6200);
FORCEPROP 1 LAST PATH I147
J 0
(5750 6525);
DISPLAY 0.978723 (5750 6525);
PAINT WHITE (5750 6525);
DISPLAY INVISIBLE (5750 6525);
FORCEADD CONN4_HFK1040L0P1L7H..1
(5350 1575);
FORCEPROP 1 LAST LOCATION J8
J 0
(5275 1825);
DISPLAY 0.489362 (5275 1825);
PAINT SKYBLUE (5275 1825);
FORCEPROP 0 LAST $SEC 1
J 0
(5300 2125);
DISPLAY 0.680851 (5300 2125);
PAINT MONO (5300 2125);
DISPLAY INVISIBLE (5300 2125);
FORCEPROP 0 LAST CDS_SEC 1
J 0
(5300 2125);
DISPLAY 1.021277 (5300 2125);
DISPLAY INVISIBLE (5300 2125);
FORCEPROP 0 LASTPIN (5125 1500) $PN 1
J 2
(5115 1510);
DISPLAY 0.489362 (5115 1510);
PAINT MONO (5115 1510);
FORCEPROP 0 LASTPIN (5125 1550) $PN 2
J 2
(5115 1560);
DISPLAY 0.489362 (5115 1560);
PAINT MONO (5115 1560);
FORCEPROP 0 LASTPIN (5125 1600) $PN 3
J 2
(5115 1610);
DISPLAY 0.489362 (5115 1610);
PAINT MONO (5115 1610);
FORCEPROP 0 LASTPIN (5125 1650) $PN 4
J 2
(5115 1660);
DISPLAY 0.489362 (5115 1660);
PAINT MONO (5115 1660);
FORCEPROP 2 LAST PART_TYPE THLF
J 0
(5275 1975);
DISPLAY 1.021277 (5275 1975);
FORCEPROP 1 LAST MATERIAL IO
J 0
(5277 1716);
DISPLAY 0.489362 (5277 1716);
PAINT SKYBLUE (5277 1716);
FORCEPROP 2 LAST VALUE CONN4_HFK1040-L0P1L-7H
J 0
(5275 1900);
DISPLAY 0.489362 (5275 1900);
PAINT SKYBLUE (5275 1900);
FORCEPROP 2 LAST CDS_LIB pure_quanta
J 0
(5350 1575);
DISPLAY INVISIBLE (5350 1575);
FORCEPROP 1 LAST NEEDS_NO_SIZE TRUE
J 0
(5350 1575);
DISPLAY 0.723404 (5350 1575);
PAINT GREEN (5350 1575);
DISPLAY INVISIBLE (5350 1575);
FORCEPROP 1 LAST CDS_LMAN_SYM_OUTLINE -75,125,75,-125
J 0
(5350 1575);
DISPLAY 0.468085 (5350 1575);
PAINT GREEN (5350 1575);
DISPLAY INVISIBLE (5350 1575);
FORCEPROP 1 LAST PART_NUMBER DFHD04MS460
J 0
(5275 1775);
DISPLAY 0.489362 (5275 1775);
PAINT SKYBLUE (5275 1775);
DISPLAY INVISIBLE (5275 1775);
FORCEPROP 1 LAST PATH I148
J 0
(5350 1575);
DISPLAY 0.723404 (5350 1575);
PAINT GREEN (5350 1575);
DISPLAY INVISIBLE (5350 1575);
FORCEADD Q_RES..1
(4275 2375);
FORCEPROP 1 LAST LOCATION R3241
J 0
(4025 2375);
DISPLAY 0.808511 (4025 2375);
FORCEPROP 0 LAST $SEC 1
J 0
(4225 2475);
DISPLAY 0.680851 (4225 2475);
PAINT MONO (4225 2475);
DISPLAY INVISIBLE (4225 2475);
FORCEPROP 0 LAST CDS_SEC 1
J 0
(4225 2475);
DISPLAY 1.021277 (4225 2475);
DISPLAY INVISIBLE (4225 2475);
FORCEPROP 1 LASTPIN (4175 2375) $PN 1
J 0
(4187 2387);
DISPLAY 0.787234 (4187 2387);
PAINT MONO (4187 2387);
FORCEPROP 1 LASTPIN (4375 2375) $PN 2
J 0
(4337 2387);
DISPLAY 0.787234 (4337 2387);
PAINT MONO (4337 2387);
FORCEPROP 1 LAST VALUE 2.2K
J 2
(4500 2375);
DISPLAY 0.510638 (4500 2375);
FORCEPROP 1 LAST TOLERANCE 5%
J 0
(4500 2375);
DISPLAY 0.510638 (4500 2375);
FORCEPROP 1 LAST MATERIAL EMPTY
J 0
(4575 2375);
DISPLAY 0.510638 (4575 2375);
PAINT RED (4575 2375);
FORCEPROP 1 LAST PACK_TYPE 0402LF
J 0
(4175 2475);
DISPLAY 0.510638 (4175 2475);
DISPLAY INVISIBLE (4175 2475);
FORCEPROP 1 LAST WATTAGE 1/16W
J 2
(4475 2475);
DISPLAY 0.510638 (4475 2475);
DISPLAY INVISIBLE (4475 2475);
FORCEPROP 2 LAST CDS_LIB pure_quanta
J 0
(4275 2375);
DISPLAY INVISIBLE (4275 2375);
FORCEPROP 1 LAST PART_NUMBER CS22202JB07
J 0
(4175 2425);
DISPLAY 0.510638 (4175 2425);
DISPLAY INVISIBLE (4175 2425);
FORCEPROP 1 LAST PATH I149
J 0
(4225 2525);
DISPLAY 0.978723 (4225 2525);
PAINT WHITE (4225 2525);
DISPLAY INVISIBLE (4225 2525);
FORCEADD OFFPAGE..3
R 2
(-500 4200);
FORCEPROP 2 LAST $XR0 81 
J 0
(-779 4200);
DISPLAY 0.638298 (-779 4200);
PAINT MONO (-779 4200);
FORCEPROP 2 LAST CDS_LIB standard
J 0
(-500 4200);
DISPLAY INVISIBLE (-500 4200);
FORCEPROP 1 LAST OFFPAGE TRUE
J 2
(-825 4075);
DISPLAY 0.872340 (-825 4075);
PAINT GREEN (-825 4075);
DISPLAY INVISIBLE (-825 4075);
FORCEPROP 1 LAST COMMENT_BODY TRUE
J 2
(-450 4100);
DISPLAY 0.872340 (-450 4100);
PAINT GREEN (-450 4100);
DISPLAY INVISIBLE (-450 4100);
FORCEPROP 2 LAST PATH I15
J 0
(-775 4250);
DISPLAY 0.680851 (-775 4250);
DISPLAY INVISIBLE (-775 4250);
FORCEADD Q_RES..1
R 2
(-1125 3475);
FORCEPROP 1 LAST LOCATION R6066
J 2
(-1250 3475);
DISPLAY 0.489362 (-1250 3475);
PAINT SKYBLUE (-1250 3475);
FORCEPROP 0 LAST $SEC 1
J 0
(-1250 3525);
DISPLAY 0.680851 (-1250 3525);
PAINT MONO (-1250 3525);
DISPLAY INVISIBLE (-1250 3525);
FORCEPROP 0 LAST CDS_SEC 1
J 0
(-1250 3525);
DISPLAY 0.680851 (-1250 3525);
DISPLAY INVISIBLE (-1250 3525);
FORCEPROP 1 LASTPIN (-1025 3475) $PN 1
J 2
(-1037 3487);
DISPLAY 0.489362 (-1037 3487);
PAINT MONO (-1037 3487);
FORCEPROP 1 LASTPIN (-1225 3475) $PN 2
J 2
(-1187 3487);
DISPLAY 0.489362 (-1187 3487);
PAINT MONO (-1187 3487);
FORCEPROP 1 LAST MATERIAL EMPTY
J 2
(-825 3475);
DISPLAY 0.489362 (-825 3475);
PAINT SKYBLUE (-825 3475);
FORCEPROP 1 LAST VALUE 0
J 0
(-1025 3475);
DISPLAY 0.489362 (-1025 3475);
PAINT SKYBLUE (-1025 3475);
FORCEPROP 1 LAST PACK_TYPE 0402LF
J 2
(-1175 3400);
DISPLAY 0.489362 (-1175 3400);
PAINT SKYBLUE (-1175 3400);
DISPLAY INVISIBLE (-1175 3400);
FORCEPROP 1 LAST TOLERANCE 5%
J 2
(-1100 3400);
DISPLAY 0.489362 (-1100 3400);
PAINT SKYBLUE (-1100 3400);
DISPLAY INVISIBLE (-1100 3400);
FORCEPROP 1 LAST WATTAGE 1/16W
J 0
(-1525 3400);
DISPLAY 0.489362 (-1525 3400);
PAINT SKYBLUE (-1525 3400);
DISPLAY INVISIBLE (-1525 3400);
FORCEPROP 2 LAST CDS_LIB pure_quanta
J 0
(-1125 3475);
DISPLAY INVISIBLE (-1125 3475);
FORCEPROP 1 LAST PART_NUMBER CS00002JB13
J 2
(-1150 3525);
DISPLAY 0.489362 (-1150 3525);
PAINT SKYBLUE (-1150 3525);
DISPLAY INVISIBLE (-1150 3525);
FORCEPROP 1 LAST PATH I150
J 2
(-1075 3625);
DISPLAY 0.978723 (-1075 3625);
PAINT WHITE (-1075 3625);
DISPLAY INVISIBLE (-1075 3625);
FORCEADD Q_RES..1
R 2
(-1125 2925);
FORCEPROP 1 LAST LOCATION R6068
J 2
(-1250 2925);
DISPLAY 0.489362 (-1250 2925);
PAINT SKYBLUE (-1250 2925);
FORCEPROP 0 LAST $SEC 1
J 0
(-1250 2975);
DISPLAY 0.680851 (-1250 2975);
PAINT MONO (-1250 2975);
DISPLAY INVISIBLE (-1250 2975);
FORCEPROP 0 LAST CDS_SEC 1
J 0
(-1250 2975);
DISPLAY 0.680851 (-1250 2975);
DISPLAY INVISIBLE (-1250 2975);
FORCEPROP 1 LASTPIN (-1025 2925) $PN 1
J 2
(-1037 2937);
DISPLAY 0.489362 (-1037 2937);
PAINT MONO (-1037 2937);
FORCEPROP 1 LASTPIN (-1225 2925) $PN 2
J 2
(-1187 2937);
DISPLAY 0.489362 (-1187 2937);
PAINT MONO (-1187 2937);
FORCEPROP 1 LAST VALUE 0
J 0
(-1025 2925);
DISPLAY 0.489362 (-1025 2925);
PAINT SKYBLUE (-1025 2925);
FORCEPROP 1 LAST MATERIAL EMPTY
J 2
(-825 2925);
DISPLAY 0.489362 (-825 2925);
PAINT SKYBLUE (-825 2925);
FORCEPROP 2 LAST CDS_LIB pure_quanta
J 0
(-1125 2925);
DISPLAY INVISIBLE (-1125 2925);
FORCEPROP 1 LAST WATTAGE 1/16W
J 0
(-1525 2850);
DISPLAY 0.489362 (-1525 2850);
PAINT SKYBLUE (-1525 2850);
DISPLAY INVISIBLE (-1525 2850);
FORCEPROP 1 LAST TOLERANCE 5%
J 2
(-1100 2850);
DISPLAY 0.489362 (-1100 2850);
PAINT SKYBLUE (-1100 2850);
DISPLAY INVISIBLE (-1100 2850);
FORCEPROP 1 LAST PACK_TYPE 0402LF
J 2
(-1175 2850);
DISPLAY 0.489362 (-1175 2850);
PAINT SKYBLUE (-1175 2850);
DISPLAY INVISIBLE (-1175 2850);
FORCEPROP 1 LAST PART_NUMBER CS00002JB13
J 2
(-1150 2975);
DISPLAY 0.489362 (-1150 2975);
PAINT SKYBLUE (-1150 2975);
DISPLAY INVISIBLE (-1150 2975);
FORCEPROP 1 LAST PATH I151
J 2
(-1075 3075);
DISPLAY 0.978723 (-1075 3075);
PAINT WHITE (-1075 3075);
DISPLAY INVISIBLE (-1075 3075);
FORCEADD OFFPAGE..2
R 2
(-2075 2925);
FORCEPROP 2 LAST $XR0 171 
J 0
(-2330 2925);
DISPLAY 0.638298 (-2330 2925);
PAINT MONO (-2330 2925);
FORCEPROP 2 LAST CDS_LIB standard
J 0
(-2075 2925);
DISPLAY INVISIBLE (-2075 2925);
FORCEPROP 1 LAST OFFPAGE TRUE
J 2
(-2400 2800);
DISPLAY 0.872340 (-2400 2800);
DISPLAY INVISIBLE (-2400 2800);
FORCEPROP 1 LAST COMMENT_BODY TRUE
J 2
(-2030 2830);
DISPLAY 0.872340 (-2030 2830);
PAINT GREEN (-2030 2830);
DISPLAY INVISIBLE (-2030 2830);
FORCEPROP 2 LAST PATH I152
J 0
(-2325 2975);
DISPLAY 0.680851 (-2325 2975);
DISPLAY INVISIBLE (-2325 2975);
FORCEADD OFFPAGE..1
(-2100 3475);
FORCEPROP 2 LAST $XR0 171 
J 0
(-2382 3475);
DISPLAY 0.638298 (-2382 3475);
PAINT MONO (-2382 3475);
FORCEPROP 2 LAST CDS_LIB standard
J 2
(-2100 3475);
DISPLAY INVISIBLE (-2100 3475);
FORCEPROP 1 LAST OFFPAGE TRUE
J 0
(-1775 3350);
DISPLAY 0.872340 (-1775 3350);
DISPLAY INVISIBLE (-1775 3350);
FORCEPROP 1 LAST COMMENT_BODY TRUE
J 0
(-1975 3375);
DISPLAY 0.872340 (-1975 3375);
PAINT GREEN (-1975 3375);
DISPLAY INVISIBLE (-1975 3375);
FORCEPROP 2 LAST PATH I153
J 0
(-2050 3550);
DISPLAY 0.680851 (-2050 3550);
DISPLAY INVISIBLE (-2050 3550);
FORCEADD OFFPAGE..2
(-250 2925);
FORCEPROP 2 LAST $XR0 150 
J 0
(-61 2925);
DISPLAY 0.638298 (-61 2925);
PAINT MONO (-61 2925);
FORCEPROP 2 LAST CDS_LIB standard
J 0
(-250 2925);
DISPLAY INVISIBLE (-250 2925);
FORCEPROP 1 LAST OFFPAGE TRUE
J 0
(75 2800);
DISPLAY 0.872340 (75 2800);
PAINT GREEN (75 2800);
DISPLAY INVISIBLE (75 2800);
FORCEPROP 1 LAST COMMENT_BODY TRUE
J 0
(-295 2830);
DISPLAY 0.872340 (-295 2830);
PAINT GREEN (-295 2830);
DISPLAY INVISIBLE (-295 2830);
FORCEPROP 2 LAST PATH I156
J 0
(-50 2975);
DISPLAY 0.680851 (-50 2975);
DISPLAY INVISIBLE (-50 2975);
FORCEADD OFFPAGE..1
R 2
(500 3475);
FORCEPROP 2 LAST $XR0 150 
J 0
(686 3475);
DISPLAY 0.638298 (686 3475);
PAINT MONO (686 3475);
FORCEPROP 2 LAST CDS_LIB standard
J 2
(500 3475);
DISPLAY INVISIBLE (500 3475);
FORCEPROP 1 LAST OFFPAGE TRUE
J 2
(175 3350);
DISPLAY 0.872340 (175 3350);
DISPLAY INVISIBLE (175 3350);
FORCEPROP 1 LAST COMMENT_BODY TRUE
J 2
(375 3375);
DISPLAY 0.872340 (375 3375);
PAINT GREEN (375 3375);
DISPLAY INVISIBLE (375 3375);
FORCEPROP 2 LAST PATH I157
J 2
(300 3525);
DISPLAY 0.680851 (300 3525);
DISPLAY INVISIBLE (300 3525);
FORCEADD Q_RES..1
R 2
(-1125 2750);
FORCEPROP 1 LAST LOCATION R6069
J 2
(-1250 2750);
DISPLAY 0.489362 (-1250 2750);
PAINT SKYBLUE (-1250 2750);
FORCEPROP 0 LAST $SEC 1
J 0
(-1250 2800);
DISPLAY 0.680851 (-1250 2800);
PAINT MONO (-1250 2800);
DISPLAY INVISIBLE (-1250 2800);
FORCEPROP 0 LAST CDS_SEC 1
J 0
(-1250 2800);
DISPLAY 0.680851 (-1250 2800);
DISPLAY INVISIBLE (-1250 2800);
FORCEPROP 1 LASTPIN (-1025 2750) $PN 1
J 2
(-1037 2762);
DISPLAY 0.489362 (-1037 2762);
PAINT MONO (-1037 2762);
FORCEPROP 1 LASTPIN (-1225 2750) $PN 2
J 2
(-1187 2762);
DISPLAY 0.489362 (-1187 2762);
PAINT MONO (-1187 2762);
FORCEPROP 1 LAST VALUE 0
J 0
(-1025 2750);
DISPLAY 0.489362 (-1025 2750);
PAINT SKYBLUE (-1025 2750);
FORCEPROP 1 LAST MATERIAL CHIP
J 2
(-850 2750);
DISPLAY 0.489362 (-850 2750);
PAINT SKYBLUE (-850 2750);
FORCEPROP 2 LAST CDS_LIB pure_quanta
J 0
(-1125 2750);
DISPLAY INVISIBLE (-1125 2750);
FORCEPROP 1 LAST WATTAGE 1/16W
J 0
(-1525 2675);
DISPLAY 0.489362 (-1525 2675);
PAINT SKYBLUE (-1525 2675);
DISPLAY INVISIBLE (-1525 2675);
FORCEPROP 1 LAST TOLERANCE 5%
J 2
(-1100 2675);
DISPLAY 0.489362 (-1100 2675);
PAINT SKYBLUE (-1100 2675);
DISPLAY INVISIBLE (-1100 2675);
FORCEPROP 1 LAST PACK_TYPE 0402LF
J 2
(-1175 2675);
DISPLAY 0.489362 (-1175 2675);
PAINT SKYBLUE (-1175 2675);
DISPLAY INVISIBLE (-1175 2675);
FORCEPROP 1 LAST PART_NUMBER CS00002JB13
J 2
(-1150 2800);
DISPLAY 0.489362 (-1150 2800);
PAINT SKYBLUE (-1150 2800);
DISPLAY INVISIBLE (-1150 2800);
FORCEPROP 1 LAST PATH I158
J 2
(-1075 2900);
DISPLAY 0.978723 (-1075 2900);
PAINT WHITE (-1075 2900);
DISPLAY INVISIBLE (-1075 2900);
FORCEADD Q_RES..1
R 2
(-1125 3325);
FORCEPROP 1 LAST LOCATION R6067
J 2
(-1250 3325);
DISPLAY 0.489362 (-1250 3325);
PAINT SKYBLUE (-1250 3325);
FORCEPROP 0 LAST $SEC 1
J 0
(-1250 3375);
DISPLAY 0.680851 (-1250 3375);
PAINT MONO (-1250 3375);
DISPLAY INVISIBLE (-1250 3375);
FORCEPROP 0 LAST CDS_SEC 1
J 0
(-1250 3375);
DISPLAY 0.680851 (-1250 3375);
DISPLAY INVISIBLE (-1250 3375);
FORCEPROP 1 LASTPIN (-1025 3325) $PN 1
J 2
(-1037 3337);
DISPLAY 0.489362 (-1037 3337);
PAINT MONO (-1037 3337);
FORCEPROP 1 LASTPIN (-1225 3325) $PN 2
J 2
(-1187 3337);
DISPLAY 0.489362 (-1187 3337);
PAINT MONO (-1187 3337);
FORCEPROP 1 LAST MATERIAL CHIP
J 2
(-850 3325);
DISPLAY 0.489362 (-850 3325);
PAINT SKYBLUE (-850 3325);
FORCEPROP 1 LAST VALUE 0
J 0
(-1025 3325);
DISPLAY 0.489362 (-1025 3325);
PAINT SKYBLUE (-1025 3325);
FORCEPROP 2 LAST CDS_LIB pure_quanta
J 0
(-1125 3325);
DISPLAY INVISIBLE (-1125 3325);
FORCEPROP 1 LAST WATTAGE 1/16W
J 0
(-1525 3250);
DISPLAY 0.489362 (-1525 3250);
PAINT SKYBLUE (-1525 3250);
DISPLAY INVISIBLE (-1525 3250);
FORCEPROP 1 LAST TOLERANCE 5%
J 2
(-1100 3250);
DISPLAY 0.489362 (-1100 3250);
PAINT SKYBLUE (-1100 3250);
DISPLAY INVISIBLE (-1100 3250);
FORCEPROP 1 LAST PACK_TYPE 0402LF
J 2
(-1175 3250);
DISPLAY 0.489362 (-1175 3250);
PAINT SKYBLUE (-1175 3250);
DISPLAY INVISIBLE (-1175 3250);
FORCEPROP 1 LAST PART_NUMBER CS00002JB13
J 2
(-1150 3375);
DISPLAY 0.489362 (-1150 3375);
PAINT SKYBLUE (-1150 3375);
DISPLAY INVISIBLE (-1150 3375);
FORCEPROP 1 LAST PATH I159
J 2
(-1075 3475);
DISPLAY 0.978723 (-1075 3475);
PAINT WHITE (-1075 3475);
DISPLAY INVISIBLE (-1075 3475);
FORCEADD OFFPAGE..2
R 2
(-525 4300);
FORCEPROP 2 LAST $XR0 81 
J 0
(-779 4300);
DISPLAY 0.638298 (-779 4300);
PAINT MONO (-779 4300);
FORCEPROP 2 LAST CDS_LIB standard
J 0
(-525 4300);
DISPLAY INVISIBLE (-525 4300);
FORCEPROP 1 LAST OFFPAGE TRUE
J 2
(-850 4175);
DISPLAY 0.872340 (-850 4175);
PAINT GREEN (-850 4175);
DISPLAY INVISIBLE (-850 4175);
FORCEPROP 1 LAST COMMENT_BODY TRUE
J 2
(-480 4205);
DISPLAY 0.872340 (-480 4205);
PAINT GREEN (-480 4205);
DISPLAY INVISIBLE (-480 4205);
FORCEPROP 2 LAST PATH I16
J 0
(-775 4350);
DISPLAY 0.680851 (-775 4350);
DISPLAY INVISIBLE (-775 4350);
FORCEADD OFFPAGE..2
(-1025 5350);
FORCEPROP 2 LAST $XR1 172 
J 0
(-716 5350);
DISPLAY 0.638298 (-716 5350);
PAINT MONO (-716 5350);
FORCEPROP 2 LAST $XR0 150 
J 0
(-836 5350);
DISPLAY 0.638298 (-836 5350);
PAINT MONO (-836 5350);
FORCEPROP 2 LAST CDS_LIB standard
J 0
(-1025 5350);
DISPLAY INVISIBLE (-1025 5350);
FORCEPROP 1 LAST OFFPAGE TRUE
J 0
(-700 5225);
DISPLAY 0.872340 (-700 5225);
PAINT GREEN (-700 5225);
DISPLAY INVISIBLE (-700 5225);
FORCEPROP 1 LAST COMMENT_BODY TRUE
J 0
(-1070 5255);
DISPLAY 0.872340 (-1070 5255);
PAINT PEACH (-1070 5255);
DISPLAY INVISIBLE (-1070 5255);
FORCEPROP 2 LAST PATH I160
J 0
(-700 5400);
DISPLAY 0.680851 (-700 5400);
DISPLAY INVISIBLE (-700 5400);
FORCEADD Q_RES..1
(-2100 5350);
FORCEPROP 1 LAST LOCATION R6070
J 0
(-2350 5350);
DISPLAY 0.489362 (-2350 5350);
PAINT SKYBLUE (-2350 5350);
FORCEPROP 0 LAST $SEC 1
J 0
(-1975 5375);
DISPLAY 0.680851 (-1975 5375);
PAINT MONO (-1975 5375);
DISPLAY INVISIBLE (-1975 5375);
FORCEPROP 0 LAST CDS_SEC 1
J 0
(-1975 5375);
DISPLAY 0.680851 (-1975 5375);
DISPLAY INVISIBLE (-1975 5375);
FORCEPROP 1 LASTPIN (-2200 5350) $PN 1
J 0
(-2188 5362);
DISPLAY 0.787234 (-2188 5362);
PAINT MONO (-2188 5362);
FORCEPROP 1 LASTPIN (-2000 5350) $PN 2
J 0
(-2038 5362);
DISPLAY 0.787234 (-2038 5362);
PAINT MONO (-2038 5362);
FORCEPROP 1 LAST MATERIAL EMPTY
J 0
(-2000 5325);
DISPLAY 0.489362 (-2000 5325);
PAINT SKYBLUE (-2000 5325);
FORCEPROP 1 LAST VALUE 4.7K
J 0
(-1975 5350);
DISPLAY 0.489362 (-1975 5350);
PAINT SKYBLUE (-1975 5350);
FORCEPROP 2 LAST CDS_LIB pure_quanta
J 0
(-2100 5350);
DISPLAY INVISIBLE (-2100 5350);
FORCEPROP 1 LAST PACK_TYPE 0402LF
J 0
(-1850 5200);
DISPLAY 0.510638 (-1850 5200);
PAINT SKYBLUE (-1850 5200);
DISPLAY INVISIBLE (-1850 5200);
FORCEPROP 1 LAST TOLERANCE 5%
J 0
(-1975 5350);
DISPLAY 0.510638 (-1975 5350);
PAINT SKYBLUE (-1975 5350);
DISPLAY INVISIBLE (-1975 5350);
FORCEPROP 1 LAST WATTAGE 1/16W
J 2
(-2125 5200);
DISPLAY 0.510638 (-2125 5200);
PAINT SKYBLUE (-2125 5200);
DISPLAY INVISIBLE (-2125 5200);
FORCEPROP 1 LAST PART_NUMBER CS24702JB10
J 0
(-2150 5450);
DISPLAY 0.510638 (-2150 5450);
PAINT SKYBLUE (-2150 5450);
DISPLAY INVISIBLE (-2150 5450);
FORCEPROP 1 LAST PATH I161
J 0
(-2150 5500);
DISPLAY 0.978723 (-2150 5500);
PAINT WHITE (-2150 5500);
DISPLAY INVISIBLE (-2150 5500);
FORCEADD Q_RES..1
(-250 4550);
FORCEPROP 1 LAST LOCATION R633
J 0
(-475 4550);
DISPLAY 0.489362 (-475 4550);
PAINT SKYBLUE (-475 4550);
FORCEPROP 0 LAST $SEC 1
J 0
(-375 4600);
DISPLAY 0.680851 (-375 4600);
PAINT MONO (-375 4600);
DISPLAY INVISIBLE (-375 4600);
FORCEPROP 0 LAST CDS_SEC 1
J 0
(-375 4600);
DISPLAY 1.021277 (-375 4600);
DISPLAY INVISIBLE (-375 4600);
FORCEPROP 1 LASTPIN (-350 4550) $PN 1
J 0
(-338 4562);
DISPLAY 0.489362 (-338 4562);
PAINT MONO (-338 4562);
FORCEPROP 1 LASTPIN (-150 4550) $PN 2
J 0
(-188 4562);
DISPLAY 0.489362 (-188 4562);
PAINT MONO (-188 4562);
FORCEPROP 1 LAST VALUE 2.2K
J 0
(-125 4550);
DISPLAY 0.489362 (-125 4550);
PAINT SKYBLUE (-125 4550);
FORCEPROP 1 LAST MATERIAL CHIP
J 0
(-625 4550);
DISPLAY 0.489362 (-625 4550);
PAINT SKYBLUE (-625 4550);
FORCEPROP 1 LAST PACK_TYPE 0402LF
J 0
(0 4400);
DISPLAY 0.510638 (0 4400);
PAINT SKYBLUE (0 4400);
DISPLAY INVISIBLE (0 4400);
FORCEPROP 1 LAST TOLERANCE 5%
J 0
(-125 4550);
DISPLAY 0.510638 (-125 4550);
PAINT SKYBLUE (-125 4550);
DISPLAY INVISIBLE (-125 4550);
FORCEPROP 1 LAST WATTAGE 1/16W
J 2
(-275 4400);
DISPLAY 0.510638 (-275 4400);
PAINT SKYBLUE (-275 4400);
DISPLAY INVISIBLE (-275 4400);
FORCEPROP 2 LAST CDS_LIB pure_quanta
J 0
(-250 4550);
DISPLAY INVISIBLE (-250 4550);
FORCEPROP 1 LAST PART_NUMBER CS22202JB07
J 0
(-300 4650);
DISPLAY 0.510638 (-300 4650);
PAINT SKYBLUE (-300 4650);
DISPLAY INVISIBLE (-300 4650);
FORCEPROP 1 LAST PATH I17
J 0
(-300 4700);
DISPLAY 0.978723 (-300 4700);
PAINT WHITE (-300 4700);
DISPLAY INVISIBLE (-300 4700);
FORCEADD Q_RES..1
(2700 6550);
FORCEPROP 1 LAST LOCATION R348
J 0
(2450 6550);
DISPLAY 0.638298 (2450 6550);
FORCEPROP 0 LAST $SEC 1
J 0
(2450 6600);
DISPLAY 0.680851 (2450 6600);
PAINT MONO (2450 6600);
DISPLAY INVISIBLE (2450 6600);
FORCEPROP 0 LAST CDS_SEC 1
J 0
(2450 6600);
DISPLAY 0.680851 (2450 6600);
DISPLAY INVISIBLE (2450 6600);
FORCEPROP 1 LASTPIN (2600 6550) $PN 1
J 0
(2612 6562);
DISPLAY 0.787234 (2612 6562);
PAINT MONO (2612 6562);
FORCEPROP 1 LASTPIN (2800 6550) $PN 2
J 0
(2762 6562);
DISPLAY 0.787234 (2762 6562);
PAINT MONO (2762 6562);
FORCEPROP 1 LAST TOLERANCE 1%
J 0
(2925 6550);
DISPLAY 0.510638 (2925 6550);
FORCEPROP 1 LAST VALUE 33.2
J 2
(2900 6550);
DISPLAY 0.510638 (2900 6550);
FORCEPROP 1 LAST MATERIAL CHIP
J 0
(3000 6550);
DISPLAY 0.510638 (3000 6550);
FORCEPROP 2 LAST CDS_LIB pure_quanta
J 0
(2700 6550);
DISPLAY INVISIBLE (2700 6550);
FORCEPROP 1 LAST PACK_TYPE 0402LF
J 0
(3050 6550);
DISPLAY 0.638298 (3050 6550);
DISPLAY INVISIBLE (3050 6550);
FORCEPROP 1 LAST WATTAGE 1/16W
J 2
(2900 6650);
DISPLAY 0.638298 (2900 6650);
DISPLAY INVISIBLE (2900 6650);
FORCEPROP 1 LAST PART_NUMBER CS03322FB03
J 0
(2575 6600);
DISPLAY 0.638298 (2575 6600);
DISPLAY INVISIBLE (2575 6600);
FORCEPROP 1 LAST PATH I172
J 0
(2650 6700);
DISPLAY 0.978723 (2650 6700);
PAINT WHITE (2650 6700);
DISPLAY INVISIBLE (2650 6700);
FORCEADD Q_RES..1
(2700 6600);
FORCEPROP 1 LAST LOCATION R347
J 0
(2450 6600);
DISPLAY 0.638298 (2450 6600);
FORCEPROP 0 LAST $SEC 1
J 0
(2875 6700);
DISPLAY 0.680851 (2875 6700);
PAINT MONO (2875 6700);
DISPLAY INVISIBLE (2875 6700);
FORCEPROP 0 LAST CDS_SEC 1
J 0
(2875 6700);
DISPLAY 0.680851 (2875 6700);
DISPLAY INVISIBLE (2875 6700);
FORCEPROP 1 LASTPIN (2600 6600) $PN 1
J 0
(2612 6612);
DISPLAY 0.787234 (2612 6612);
PAINT MONO (2612 6612);
FORCEPROP 1 LASTPIN (2800 6600) $PN 2
J 0
(2762 6612);
DISPLAY 0.787234 (2762 6612);
PAINT MONO (2762 6612);
FORCEPROP 1 LAST VALUE 33.2
J 2
(2900 6600);
DISPLAY 0.510638 (2900 6600);
FORCEPROP 1 LAST MATERIAL CHIP
J 0
(3000 6600);
DISPLAY 0.510638 (3000 6600);
FORCEPROP 1 LAST TOLERANCE 1%
J 0
(2925 6600);
DISPLAY 0.510638 (2925 6600);
FORCEPROP 1 LAST PACK_TYPE 0402LF
J 0
(2575 6675);
DISPLAY 0.510638 (2575 6675);
FORCEPROP 1 LAST WATTAGE 1/16W
J 2
(2875 6675);
DISPLAY 0.510638 (2875 6675);
FORCEPROP 2 LAST CDS_LIB pure_quanta
J 0
(2700 6600);
DISPLAY INVISIBLE (2700 6600);
FORCEPROP 1 LAST PART_NUMBER CS03322FB03
J 0
(2575 6675);
DISPLAY 0.510638 (2575 6675);
DISPLAY INVISIBLE (2575 6675);
FORCEPROP 1 LAST PATH I173
J 0
(2650 6750);
DISPLAY 0.978723 (2650 6750);
PAINT WHITE (2650 6750);
DISPLAY INVISIBLE (2650 6750);
FORCEADD OFFPAGE..3
(3850 6550);
FORCEPROP 2 LAST $XR1 269 
J 0
(4184 6550);
DISPLAY 0.638298 (4184 6550);
PAINT MONO (4184 6550);
FORCEPROP 2 LAST $XR0 268 
J 0
(4064 6550);
DISPLAY 0.638298 (4064 6550);
PAINT MONO (4064 6550);
FORCEPROP 2 LAST CDS_LIB standard
J 0
(3850 6550);
DISPLAY INVISIBLE (3850 6550);
FORCEPROP 1 LAST OFFPAGE TRUE
J 0
(4175 6425);
DISPLAY 0.872340 (4175 6425);
DISPLAY INVISIBLE (4175 6425);
FORCEPROP 1 LAST COMMENT_BODY TRUE
J 0
(3800 6450);
DISPLAY 0.872340 (3800 6450);
PAINT GREEN (3800 6450);
DISPLAY INVISIBLE (3800 6450);
FORCEPROP 2 LAST PATH I174
J 0
(4050 6625);
DISPLAY 0.680851 (4050 6625);
DISPLAY INVISIBLE (4050 6625);
FORCEADD OFFPAGE..2
(3875 6600);
FORCEPROP 2 LAST $XR1 269 
J 0
(4184 6600);
DISPLAY 0.638298 (4184 6600);
PAINT MONO (4184 6600);
FORCEPROP 2 LAST $XR0 268 
J 0
(4064 6600);
DISPLAY 0.638298 (4064 6600);
PAINT MONO (4064 6600);
FORCEPROP 2 LAST CDS_LIB standard
J 0
(3875 6600);
DISPLAY INVISIBLE (3875 6600);
FORCEPROP 1 LAST OFFPAGE TRUE
J 0
(4200 6475);
DISPLAY 1.170213 (4200 6475);
PAINT GREEN (4200 6475);
DISPLAY INVISIBLE (4200 6475);
FORCEPROP 1 LAST COMMENT_BODY TRUE
J 0
(3830 6505);
DISPLAY 1.170213 (3830 6505);
PAINT GREEN (3830 6505);
DISPLAY INVISIBLE (3830 6505);
FORCEPROP 2 LAST PATH I175
J 0
(4050 6675);
DISPLAY 0.680851 (4050 6675);
DISPLAY INVISIBLE (4050 6675);
FORCEADD Q_RES..1
(-1650 1700);
FORCEPROP 1 LAST LOCATION R1497
J 0
(-1925 1725);
DISPLAY 0.617021 (-1925 1725);
PAINT SKYBLUE (-1925 1725);
FORCEPROP 0 LAST $SEC 1
J 0
(-1450 1725);
DISPLAY 0.680851 (-1450 1725);
PAINT MONO (-1450 1725);
DISPLAY INVISIBLE (-1450 1725);
FORCEPROP 0 LAST CDS_SEC 1
J 0
(-1450 1725);
DISPLAY 0.680851 (-1450 1725);
DISPLAY INVISIBLE (-1450 1725);
FORCEPROP 1 LASTPIN (-1750 1700) $PN 1
J 0
(-1738 1712);
DISPLAY 0.617021 (-1738 1712);
PAINT MONO (-1738 1712);
FORCEPROP 1 LASTPIN (-1550 1700) $PN 2
J 0
(-1588 1712);
DISPLAY 0.617021 (-1588 1712);
PAINT MONO (-1588 1712);
FORCEPROP 1 LAST VALUE 33
J 2
(-1450 1700);
DISPLAY 0.617021 (-1450 1700);
PAINT SKYBLUE (-1450 1700);
FORCEPROP 2 LAST CDS_LIB pure_quanta
J 0
(-1650 1700);
DISPLAY INVISIBLE (-1650 1700);
FORCEPROP 1 LAST WATTAGE 1/16W
J 2
(-1250 1625);
DISPLAY 0.489362 (-1250 1625);
PAINT SKYBLUE (-1250 1625);
DISPLAY INVISIBLE (-1250 1625);
FORCEPROP 1 LAST MATERIAL CHIP
J 0
(-1225 1625);
DISPLAY 0.489362 (-1225 1625);
PAINT SKYBLUE (-1225 1625);
DISPLAY INVISIBLE (-1225 1625);
FORCEPROP 1 LAST TOLERANCE 5%
J 0
(-1675 1625);
DISPLAY 0.489362 (-1675 1625);
PAINT SKYBLUE (-1675 1625);
DISPLAY INVISIBLE (-1675 1625);
FORCEPROP 1 LAST PACK_TYPE 0402LF
J 0
(-1600 1625);
DISPLAY 0.489362 (-1600 1625);
PAINT SKYBLUE (-1600 1625);
DISPLAY INVISIBLE (-1600 1625);
FORCEPROP 1 LAST PART_NUMBER CS03302JB10
J 0
(-1625 1750);
DISPLAY 0.489362 (-1625 1750);
PAINT SKYBLUE (-1625 1750);
DISPLAY INVISIBLE (-1625 1750);
FORCEPROP 1 LAST PATH I176
J 0
(-1700 1850);
DISPLAY 0.978723 (-1700 1850);
PAINT WHITE (-1700 1850);
DISPLAY INVISIBLE (-1700 1850);
FORCEADD OFFPAGE..2
(-375 1450);
FORCEPROP 2 LAST $XR0 258 
J 0
(-186 1450);
DISPLAY 0.638298 (-186 1450);
PAINT MONO (-186 1450);
FORCEPROP 2 LAST CDS_LIB standard
J 0
(-375 1450);
DISPLAY INVISIBLE (-375 1450);
FORCEPROP 1 LAST OFFPAGE TRUE
J 0
(-50 1325);
DISPLAY 0.872340 (-50 1325);
PAINT GREEN (-50 1325);
DISPLAY INVISIBLE (-50 1325);
FORCEPROP 1 LAST COMMENT_BODY TRUE
J 0
(-420 1355);
DISPLAY 0.872340 (-420 1355);
PAINT GREEN (-420 1355);
DISPLAY INVISIBLE (-420 1355);
FORCEPROP 2 LAST PATH I177
J 0
(-175 1500);
DISPLAY 0.680851 (-175 1500);
DISPLAY INVISIBLE (-175 1500);
FORCEADD OFFPAGE..3
(-375 1350);
FORCEPROP 2 LAST $XR0 258 
J 0
(-161 1350);
DISPLAY 0.638298 (-161 1350);
PAINT MONO (-161 1350);
FORCEPROP 2 LAST CDS_LIB standard
J 0
(-375 1350);
DISPLAY INVISIBLE (-375 1350);
FORCEPROP 1 LAST OFFPAGE TRUE
J 0
(-50 1225);
DISPLAY 0.872340 (-50 1225);
PAINT GREEN (-50 1225);
DISPLAY INVISIBLE (-50 1225);
FORCEPROP 1 LAST COMMENT_BODY TRUE
J 0
(-425 1250);
DISPLAY 0.872340 (-425 1250);
PAINT GREEN (-425 1250);
DISPLAY INVISIBLE (-425 1250);
FORCEPROP 2 LAST PATH I178
J 0
(-150 1400);
DISPLAY 0.680851 (-150 1400);
DISPLAY INVISIBLE (-150 1400);
FORCEADD OFFPAGE..2
(-725 1700);
FORCEPROP 2 LAST $XR0 193 
J 0
(-536 1700);
DISPLAY 0.638298 (-536 1700);
PAINT MONO (-536 1700);
FORCEPROP 2 LAST CDS_LIB standard
J 0
(-725 1700);
DISPLAY INVISIBLE (-725 1700);
FORCEPROP 1 LAST OFFPAGE TRUE
J 0
(-400 1575);
DISPLAY 0.872340 (-400 1575);
PAINT GREEN (-400 1575);
DISPLAY INVISIBLE (-400 1575);
FORCEPROP 1 LAST COMMENT_BODY TRUE
J 0
(-770 1605);
DISPLAY 0.872340 (-770 1605);
PAINT GREEN (-770 1605);
DISPLAY INVISIBLE (-770 1605);
FORCEPROP 2 LAST PATH I179
J 0
(-525 1750);
DISPLAY 0.680851 (-525 1750);
DISPLAY INVISIBLE (-525 1750);
FORCEADD Q_RES..1
(-250 4600);
FORCEPROP 1 LAST LOCATION R632
J 0
(-475 4600);
DISPLAY 0.489362 (-475 4600);
PAINT SKYBLUE (-475 4600);
FORCEPROP 0 LAST $SEC 1
J 0
(-375 4650);
DISPLAY 0.680851 (-375 4650);
PAINT MONO (-375 4650);
DISPLAY INVISIBLE (-375 4650);
FORCEPROP 0 LAST CDS_SEC 1
J 0
(-375 4650);
DISPLAY 1.021277 (-375 4650);
DISPLAY INVISIBLE (-375 4650);
FORCEPROP 1 LASTPIN (-350 4600) $PN 1
J 0
(-338 4612);
DISPLAY 0.489362 (-338 4612);
PAINT MONO (-338 4612);
FORCEPROP 1 LASTPIN (-150 4600) $PN 2
J 0
(-188 4612);
DISPLAY 0.489362 (-188 4612);
PAINT MONO (-188 4612);
FORCEPROP 1 LAST VALUE 2.2K
J 0
(-125 4600);
DISPLAY 0.489362 (-125 4600);
PAINT SKYBLUE (-125 4600);
FORCEPROP 1 LAST MATERIAL CHIP
J 0
(-625 4600);
DISPLAY 0.489362 (-625 4600);
PAINT SKYBLUE (-625 4600);
FORCEPROP 1 LAST PACK_TYPE 0402LF
J 0
(0 4450);
DISPLAY 0.510638 (0 4450);
PAINT SKYBLUE (0 4450);
DISPLAY INVISIBLE (0 4450);
FORCEPROP 1 LAST TOLERANCE 5%
J 0
(-125 4600);
DISPLAY 0.510638 (-125 4600);
PAINT SKYBLUE (-125 4600);
DISPLAY INVISIBLE (-125 4600);
FORCEPROP 1 LAST WATTAGE 1/16W
J 2
(-275 4450);
DISPLAY 0.510638 (-275 4450);
PAINT SKYBLUE (-275 4450);
DISPLAY INVISIBLE (-275 4450);
FORCEPROP 2 LAST CDS_LIB pure_quanta
J 0
(-250 4600);
DISPLAY INVISIBLE (-250 4600);
FORCEPROP 1 LAST PART_NUMBER CS22202JB07
J 0
(-300 4700);
DISPLAY 0.510638 (-300 4700);
PAINT SKYBLUE (-300 4700);
DISPLAY INVISIBLE (-300 4700);
FORCEPROP 1 LAST PATH I18
J 0
(-300 4750);
DISPLAY 0.978723 (-300 4750);
PAINT WHITE (-300 4750);
DISPLAY INVISIBLE (-300 4750);
FORCEADD OFFPAGE..3
(-725 1600);
FORCEPROP 2 LAST $XR0 193 
J 0
(-511 1600);
DISPLAY 0.638298 (-511 1600);
PAINT MONO (-511 1600);
FORCEPROP 2 LAST CDS_LIB standard
J 0
(-725 1600);
DISPLAY INVISIBLE (-725 1600);
FORCEPROP 1 LAST OFFPAGE TRUE
J 0
(-400 1475);
DISPLAY 0.872340 (-400 1475);
PAINT GREEN (-400 1475);
DISPLAY INVISIBLE (-400 1475);
FORCEPROP 1 LAST COMMENT_BODY TRUE
J 0
(-775 1500);
DISPLAY 0.872340 (-775 1500);
PAINT GREEN (-775 1500);
DISPLAY INVISIBLE (-775 1500);
FORCEPROP 2 LAST PATH I180
J 0
(-500 1650);
DISPLAY 0.680851 (-500 1650);
DISPLAY INVISIBLE (-500 1650);
FORCEADD Q_RES..1
(-1125 1450);
FORCEPROP 1 LAST LOCATION R6076
J 0
(-1350 1450);
DISPLAY 0.617021 (-1350 1450);
PAINT SKYBLUE (-1350 1450);
FORCEPROP 0 LAST $SEC 1
J 0
(-925 1475);
DISPLAY 0.680851 (-925 1475);
PAINT MONO (-925 1475);
DISPLAY INVISIBLE (-925 1475);
FORCEPROP 0 LAST CDS_SEC 1
J 0
(-925 1475);
DISPLAY 0.680851 (-925 1475);
DISPLAY INVISIBLE (-925 1475);
FORCEPROP 1 LASTPIN (-1225 1450) $PN 1
J 0
(-1213 1462);
DISPLAY 0.617021 (-1213 1462);
PAINT MONO (-1213 1462);
FORCEPROP 1 LASTPIN (-1025 1450) $PN 2
J 0
(-1063 1462);
DISPLAY 0.617021 (-1063 1462);
PAINT MONO (-1063 1462);
FORCEPROP 1 LAST VALUE 33
J 2
(-925 1450);
DISPLAY 0.617021 (-925 1450);
PAINT SKYBLUE (-925 1450);
FORCEPROP 1 LAST PACK_TYPE 0402LF
J 0
(-1075 1375);
DISPLAY 0.489362 (-1075 1375);
PAINT SKYBLUE (-1075 1375);
DISPLAY INVISIBLE (-1075 1375);
FORCEPROP 1 LAST TOLERANCE 5%
J 0
(-1150 1375);
DISPLAY 0.489362 (-1150 1375);
PAINT SKYBLUE (-1150 1375);
DISPLAY INVISIBLE (-1150 1375);
FORCEPROP 1 LAST MATERIAL CHIP
J 0
(-700 1375);
DISPLAY 0.489362 (-700 1375);
PAINT SKYBLUE (-700 1375);
DISPLAY INVISIBLE (-700 1375);
FORCEPROP 1 LAST WATTAGE 1/16W
J 2
(-725 1375);
DISPLAY 0.489362 (-725 1375);
PAINT SKYBLUE (-725 1375);
DISPLAY INVISIBLE (-725 1375);
FORCEPROP 2 LAST CDS_LIB pure_quanta
J 0
(-1125 1450);
DISPLAY INVISIBLE (-1125 1450);
FORCEPROP 1 LAST PART_NUMBER CS03302JB10
J 0
(-1100 1500);
DISPLAY 0.489362 (-1100 1500);
PAINT SKYBLUE (-1100 1500);
DISPLAY INVISIBLE (-1100 1500);
FORCEPROP 1 LAST PATH I181
J 0
(-1175 1600);
DISPLAY 0.978723 (-1175 1600);
PAINT WHITE (-1175 1600);
DISPLAY INVISIBLE (-1175 1600);
FORCEADD Q_RES..1
(-1125 1350);
FORCEPROP 1 LAST LOCATION R6077
J 0
(-1350 1350);
DISPLAY 0.617021 (-1350 1350);
PAINT SKYBLUE (-1350 1350);
FORCEPROP 0 LAST $SEC 1
J 0
(-925 1375);
DISPLAY 0.680851 (-925 1375);
PAINT MONO (-925 1375);
DISPLAY INVISIBLE (-925 1375);
FORCEPROP 0 LAST CDS_SEC 1
J 0
(-925 1375);
DISPLAY 0.680851 (-925 1375);
DISPLAY INVISIBLE (-925 1375);
FORCEPROP 1 LASTPIN (-1225 1350) $PN 1
J 0
(-1213 1362);
DISPLAY 0.617021 (-1213 1362);
PAINT MONO (-1213 1362);
FORCEPROP 1 LASTPIN (-1025 1350) $PN 2
J 0
(-1063 1362);
DISPLAY 0.617021 (-1063 1362);
PAINT MONO (-1063 1362);
FORCEPROP 1 LAST VALUE 33
J 2
(-925 1350);
DISPLAY 0.617021 (-925 1350);
PAINT SKYBLUE (-925 1350);
FORCEPROP 1 LAST PACK_TYPE 0402LF
J 0
(-1075 1275);
DISPLAY 0.489362 (-1075 1275);
PAINT SKYBLUE (-1075 1275);
DISPLAY INVISIBLE (-1075 1275);
FORCEPROP 1 LAST TOLERANCE 5%
J 0
(-1150 1275);
DISPLAY 0.489362 (-1150 1275);
PAINT SKYBLUE (-1150 1275);
DISPLAY INVISIBLE (-1150 1275);
FORCEPROP 1 LAST MATERIAL CHIP
J 0
(-700 1275);
DISPLAY 0.489362 (-700 1275);
PAINT SKYBLUE (-700 1275);
DISPLAY INVISIBLE (-700 1275);
FORCEPROP 1 LAST WATTAGE 1/16W
J 2
(-725 1275);
DISPLAY 0.489362 (-725 1275);
PAINT SKYBLUE (-725 1275);
DISPLAY INVISIBLE (-725 1275);
FORCEPROP 2 LAST CDS_LIB pure_quanta
J 0
(-1125 1350);
DISPLAY INVISIBLE (-1125 1350);
FORCEPROP 1 LAST PART_NUMBER CS03302JB10
J 0
(-1100 1400);
DISPLAY 0.489362 (-1100 1400);
PAINT SKYBLUE (-1100 1400);
DISPLAY INVISIBLE (-1100 1400);
FORCEPROP 1 LAST PATH I182
J 0
(-1175 1500);
DISPLAY 0.978723 (-1175 1500);
PAINT WHITE (-1175 1500);
DISPLAY INVISIBLE (-1175 1500);
FORCEADD Q_RES..1
(-1650 1600);
FORCEPROP 1 LAST LOCATION R1498
J 0
(-1925 1600);
DISPLAY 0.617021 (-1925 1600);
PAINT SKYBLUE (-1925 1600);
FORCEPROP 0 LAST $SEC 1
J 0
(-1450 1625);
DISPLAY 0.680851 (-1450 1625);
PAINT MONO (-1450 1625);
DISPLAY INVISIBLE (-1450 1625);
FORCEPROP 0 LAST CDS_SEC 1
J 0
(-1450 1625);
DISPLAY 0.680851 (-1450 1625);
DISPLAY INVISIBLE (-1450 1625);
FORCEPROP 1 LASTPIN (-1750 1600) $PN 1
J 0
(-1738 1612);
DISPLAY 0.617021 (-1738 1612);
PAINT MONO (-1738 1612);
FORCEPROP 1 LASTPIN (-1550 1600) $PN 2
J 0
(-1588 1612);
DISPLAY 0.617021 (-1588 1612);
PAINT MONO (-1588 1612);
FORCEPROP 1 LAST VALUE 33
J 2
(-1450 1600);
DISPLAY 0.617021 (-1450 1600);
PAINT SKYBLUE (-1450 1600);
FORCEPROP 1 LAST PACK_TYPE 0402LF
J 0
(-1600 1525);
DISPLAY 0.489362 (-1600 1525);
PAINT SKYBLUE (-1600 1525);
DISPLAY INVISIBLE (-1600 1525);
FORCEPROP 1 LAST TOLERANCE 5%
J 0
(-1675 1525);
DISPLAY 0.489362 (-1675 1525);
PAINT SKYBLUE (-1675 1525);
DISPLAY INVISIBLE (-1675 1525);
FORCEPROP 1 LAST MATERIAL CHIP
J 0
(-1225 1525);
DISPLAY 0.489362 (-1225 1525);
PAINT SKYBLUE (-1225 1525);
DISPLAY INVISIBLE (-1225 1525);
FORCEPROP 1 LAST WATTAGE 1/16W
J 2
(-1250 1525);
DISPLAY 0.489362 (-1250 1525);
PAINT SKYBLUE (-1250 1525);
DISPLAY INVISIBLE (-1250 1525);
FORCEPROP 2 LAST CDS_LIB pure_quanta
J 0
(-1650 1600);
DISPLAY INVISIBLE (-1650 1600);
FORCEPROP 1 LAST PART_NUMBER CS03302JB10
J 0
(-1625 1650);
DISPLAY 0.489362 (-1625 1650);
PAINT SKYBLUE (-1625 1650);
DISPLAY INVISIBLE (-1625 1650);
FORCEPROP 1 LAST PATH I183
J 0
(-1700 1750);
DISPLAY 0.978723 (-1700 1750);
PAINT WHITE (-1700 1750);
DISPLAY INVISIBLE (-1700 1750);
FORCEADD Q_RES..1
(1500 1425);
FORCEPROP 1 LAST LOCATION R350
J 0
(1325 1425);
DISPLAY 0.489362 (1325 1425);
PAINT SKYBLUE (1325 1425);
FORCEPROP 0 LAST $SEC 1
J 0
(1700 1450);
DISPLAY 0.680851 (1700 1450);
PAINT MONO (1700 1450);
DISPLAY INVISIBLE (1700 1450);
FORCEPROP 0 LAST CDS_SEC 1
J 0
(1700 1450);
DISPLAY 0.680851 (1700 1450);
DISPLAY INVISIBLE (1700 1450);
FORCEPROP 1 LASTPIN (1400 1425) $PN 1
J 0
(1412 1437);
DISPLAY 0.787234 (1412 1437);
PAINT MONO (1412 1437);
FORCEPROP 1 LASTPIN (1600 1425) $PN 2
J 0
(1562 1437);
DISPLAY 0.787234 (1562 1437);
PAINT MONO (1562 1437);
FORCEPROP 1 LAST VALUE 33
J 2
(1700 1425);
DISPLAY 0.489362 (1700 1425);
PAINT SKYBLUE (1700 1425);
FORCEPROP 1 LAST PACK_TYPE 0402LF
J 0
(1550 1350);
DISPLAY 0.489362 (1550 1350);
PAINT SKYBLUE (1550 1350);
DISPLAY INVISIBLE (1550 1350);
FORCEPROP 1 LAST TOLERANCE 5%
J 0
(1475 1350);
DISPLAY 0.489362 (1475 1350);
PAINT SKYBLUE (1475 1350);
DISPLAY INVISIBLE (1475 1350);
FORCEPROP 1 LAST MATERIAL CHIP
J 0
(1925 1350);
DISPLAY 0.489362 (1925 1350);
PAINT SKYBLUE (1925 1350);
DISPLAY INVISIBLE (1925 1350);
FORCEPROP 1 LAST WATTAGE 1/16W
J 2
(1900 1350);
DISPLAY 0.489362 (1900 1350);
PAINT SKYBLUE (1900 1350);
DISPLAY INVISIBLE (1900 1350);
FORCEPROP 2 LAST CDS_LIB pure_quanta
J 0
(1500 1425);
DISPLAY INVISIBLE (1500 1425);
FORCEPROP 1 LAST PART_NUMBER CS03302JB10
J 0
(1525 1475);
DISPLAY 0.489362 (1525 1475);
PAINT SKYBLUE (1525 1475);
DISPLAY INVISIBLE (1525 1475);
FORCEPROP 1 LAST PATH I184
J 0
(1450 1575);
DISPLAY 0.978723 (1450 1575);
PAINT WHITE (1450 1575);
DISPLAY INVISIBLE (1450 1575);
FORCEADD Q_RES..1
(1500 1525);
FORCEPROP 1 LAST LOCATION R349
J 0
(1325 1525);
DISPLAY 0.489362 (1325 1525);
PAINT SKYBLUE (1325 1525);
FORCEPROP 0 LAST $SEC 1
J 0
(1700 1550);
DISPLAY 0.680851 (1700 1550);
PAINT MONO (1700 1550);
DISPLAY INVISIBLE (1700 1550);
FORCEPROP 0 LAST CDS_SEC 1
J 0
(1700 1550);
DISPLAY 0.680851 (1700 1550);
DISPLAY INVISIBLE (1700 1550);
FORCEPROP 1 LASTPIN (1400 1525) $PN 1
J 0
(1412 1537);
DISPLAY 0.787234 (1412 1537);
PAINT MONO (1412 1537);
FORCEPROP 1 LASTPIN (1600 1525) $PN 2
J 0
(1562 1537);
DISPLAY 0.787234 (1562 1537);
PAINT MONO (1562 1537);
FORCEPROP 1 LAST VALUE 33
J 2
(1700 1525);
DISPLAY 0.489362 (1700 1525);
PAINT SKYBLUE (1700 1525);
FORCEPROP 1 LAST PACK_TYPE 0402LF
J 0
(1550 1450);
DISPLAY 0.489362 (1550 1450);
PAINT SKYBLUE (1550 1450);
DISPLAY INVISIBLE (1550 1450);
FORCEPROP 1 LAST TOLERANCE 5%
J 0
(1475 1450);
DISPLAY 0.489362 (1475 1450);
PAINT SKYBLUE (1475 1450);
DISPLAY INVISIBLE (1475 1450);
FORCEPROP 1 LAST MATERIAL CHIP
J 0
(1925 1450);
DISPLAY 0.489362 (1925 1450);
PAINT SKYBLUE (1925 1450);
DISPLAY INVISIBLE (1925 1450);
FORCEPROP 1 LAST WATTAGE 1/16W
J 2
(1900 1450);
DISPLAY 0.489362 (1900 1450);
PAINT SKYBLUE (1900 1450);
DISPLAY INVISIBLE (1900 1450);
FORCEPROP 2 LAST CDS_LIB pure_quanta
J 0
(1500 1525);
DISPLAY INVISIBLE (1500 1525);
FORCEPROP 1 LAST PART_NUMBER CS03302JB10
J 0
(1525 1575);
DISPLAY 0.489362 (1525 1575);
PAINT SKYBLUE (1525 1575);
DISPLAY INVISIBLE (1525 1575);
FORCEPROP 1 LAST PATH I185
J 0
(1450 1675);
DISPLAY 0.978723 (1450 1675);
PAINT WHITE (1450 1675);
DISPLAY INVISIBLE (1450 1675);
FORCEADD Q_RES..1
(2075 1025);
FORCEPROP 1 LAST LOCATION R352
J 0
(1900 1025);
DISPLAY 0.489362 (1900 1025);
PAINT SKYBLUE (1900 1025);
FORCEPROP 0 LAST $SEC 1
J 0
(2275 1050);
DISPLAY 0.680851 (2275 1050);
PAINT MONO (2275 1050);
DISPLAY INVISIBLE (2275 1050);
FORCEPROP 0 LAST CDS_SEC 1
J 0
(2275 1050);
DISPLAY 0.680851 (2275 1050);
DISPLAY INVISIBLE (2275 1050);
FORCEPROP 1 LASTPIN (1975 1025) $PN 1
J 0
(1987 1037);
DISPLAY 0.787234 (1987 1037);
PAINT MONO (1987 1037);
FORCEPROP 1 LASTPIN (2175 1025) $PN 2
J 0
(2137 1037);
DISPLAY 0.787234 (2137 1037);
PAINT MONO (2137 1037);
FORCEPROP 1 LAST VALUE 33
J 2
(2275 1025);
DISPLAY 0.489362 (2275 1025);
PAINT SKYBLUE (2275 1025);
FORCEPROP 2 LAST CDS_LIB pure_quanta
J 0
(2075 1025);
DISPLAY INVISIBLE (2075 1025);
FORCEPROP 1 LAST WATTAGE 1/16W
J 2
(2475 950);
DISPLAY 0.489362 (2475 950);
PAINT SKYBLUE (2475 950);
DISPLAY INVISIBLE (2475 950);
FORCEPROP 1 LAST MATERIAL CHIP
J 0
(2500 950);
DISPLAY 0.489362 (2500 950);
PAINT SKYBLUE (2500 950);
DISPLAY INVISIBLE (2500 950);
FORCEPROP 1 LAST TOLERANCE 5%
J 0
(2050 950);
DISPLAY 0.489362 (2050 950);
PAINT SKYBLUE (2050 950);
DISPLAY INVISIBLE (2050 950);
FORCEPROP 1 LAST PACK_TYPE 0402LF
J 0
(2125 950);
DISPLAY 0.489362 (2125 950);
PAINT SKYBLUE (2125 950);
DISPLAY INVISIBLE (2125 950);
FORCEPROP 1 LAST PART_NUMBER CS03302JB10
J 0
(2100 1075);
DISPLAY 0.489362 (2100 1075);
PAINT SKYBLUE (2100 1075);
DISPLAY INVISIBLE (2100 1075);
FORCEPROP 1 LAST PATH I186
J 0
(2025 1175);
DISPLAY 0.978723 (2025 1175);
PAINT WHITE (2025 1175);
DISPLAY INVISIBLE (2025 1175);
FORCEADD Q_RES..1
(2075 1125);
FORCEPROP 1 LAST LOCATION R351
J 0
(1900 1125);
DISPLAY 0.489362 (1900 1125);
PAINT SKYBLUE (1900 1125);
FORCEPROP 0 LAST $SEC 1
J 0
(2275 1150);
DISPLAY 0.680851 (2275 1150);
PAINT MONO (2275 1150);
DISPLAY INVISIBLE (2275 1150);
FORCEPROP 0 LAST CDS_SEC 1
J 0
(2275 1150);
DISPLAY 0.680851 (2275 1150);
DISPLAY INVISIBLE (2275 1150);
FORCEPROP 1 LASTPIN (1975 1125) $PN 1
J 0
(1987 1137);
DISPLAY 0.787234 (1987 1137);
PAINT MONO (1987 1137);
FORCEPROP 1 LASTPIN (2175 1125) $PN 2
J 0
(2137 1137);
DISPLAY 0.787234 (2137 1137);
PAINT MONO (2137 1137);
FORCEPROP 1 LAST VALUE 33
J 2
(2275 1125);
DISPLAY 0.489362 (2275 1125);
PAINT SKYBLUE (2275 1125);
FORCEPROP 2 LAST CDS_LIB pure_quanta
J 0
(2075 1125);
DISPLAY INVISIBLE (2075 1125);
FORCEPROP 1 LAST PACK_TYPE 0402LF
J 0
(2125 1050);
DISPLAY 0.489362 (2125 1050);
PAINT SKYBLUE (2125 1050);
DISPLAY INVISIBLE (2125 1050);
FORCEPROP 1 LAST TOLERANCE 5%
J 0
(2050 1050);
DISPLAY 0.489362 (2050 1050);
PAINT SKYBLUE (2050 1050);
DISPLAY INVISIBLE (2050 1050);
FORCEPROP 1 LAST MATERIAL CHIP
J 0
(2500 1050);
DISPLAY 0.489362 (2500 1050);
PAINT SKYBLUE (2500 1050);
DISPLAY INVISIBLE (2500 1050);
FORCEPROP 1 LAST WATTAGE 1/16W
J 2
(2475 1050);
DISPLAY 0.489362 (2475 1050);
PAINT SKYBLUE (2475 1050);
DISPLAY INVISIBLE (2475 1050);
FORCEPROP 1 LAST PART_NUMBER CS03302JB10
J 0
(2100 1175);
DISPLAY 0.489362 (2100 1175);
PAINT SKYBLUE (2100 1175);
DISPLAY INVISIBLE (2100 1175);
FORCEPROP 1 LAST PATH I187
J 0
(2025 1275);
DISPLAY 0.978723 (2025 1275);
PAINT WHITE (2025 1275);
DISPLAY INVISIBLE (2025 1275);
FORCEADD OFFPAGE..2
(2425 1525);
FORCEPROP 2 LAST $XR0 200 
J 0
(2614 1525);
DISPLAY 0.638298 (2614 1525);
PAINT MONO (2614 1525);
FORCEPROP 2 LAST CDS_LIB standard
J 0
(2425 1525);
DISPLAY INVISIBLE (2425 1525);
FORCEPROP 1 LAST OFFPAGE TRUE
J 0
(2750 1400);
DISPLAY 0.872340 (2750 1400);
PAINT GREEN (2750 1400);
DISPLAY INVISIBLE (2750 1400);
FORCEPROP 1 LAST COMMENT_BODY TRUE
J 0
(2380 1430);
DISPLAY 0.872340 (2380 1430);
PAINT GREEN (2380 1430);
DISPLAY INVISIBLE (2380 1430);
FORCEPROP 2 LAST PATH I188
J 0
(2600 1600);
DISPLAY 0.680851 (2600 1600);
DISPLAY INVISIBLE (2600 1600);
FORCEADD OFFPAGE..3
(2400 1425);
FORCEPROP 2 LAST $XR0 200 
J 0
(2614 1425);
DISPLAY 0.638298 (2614 1425);
PAINT MONO (2614 1425);
FORCEPROP 2 LAST CDS_LIB standard
J 0
(2400 1425);
DISPLAY INVISIBLE (2400 1425);
FORCEPROP 1 LAST OFFPAGE TRUE
J 0
(2725 1300);
DISPLAY 0.872340 (2725 1300);
PAINT GREEN (2725 1300);
DISPLAY INVISIBLE (2725 1300);
FORCEPROP 1 LAST COMMENT_BODY TRUE
J 0
(2350 1325);
DISPLAY 0.872340 (2350 1325);
PAINT GREEN (2350 1325);
DISPLAY INVISIBLE (2350 1325);
FORCEPROP 2 LAST PATH I189
J 0
(2600 1500);
DISPLAY 0.680851 (2600 1500);
DISPLAY INVISIBLE (2600 1500);
FORCEADD OFFPAGE..2
R 2
(-2475 4850);
FORCEPROP 2 LAST $XR1 80 
J 0
(-2850 4850);
DISPLAY 0.638298 (-2850 4850);
PAINT MONO (-2850 4850);
FORCEPROP 2 LAST $XR0 150 
J 0
(-2760 4850);
DISPLAY 0.638298 (-2760 4850);
PAINT MONO (-2760 4850);
FORCEPROP 2 LAST CDS_LIB standard
J 0
(-2475 4850);
DISPLAY INVISIBLE (-2475 4850);
FORCEPROP 1 LAST OFFPAGE TRUE
J 2
(-2800 4725);
DISPLAY 0.872340 (-2800 4725);
PAINT GREEN (-2800 4725);
DISPLAY INVISIBLE (-2800 4725);
FORCEPROP 1 LAST COMMENT_BODY TRUE
J 2
(-2430 4755);
DISPLAY 0.872340 (-2430 4755);
PAINT GREEN (-2430 4755);
DISPLAY INVISIBLE (-2430 4755);
FORCEPROP 2 LAST PATH I19
J 0
(-2425 4925);
DISPLAY 0.680851 (-2425 4925);
DISPLAY INVISIBLE (-2425 4925);
FORCEADD OFFPAGE..3
(2950 1025);
FORCEPROP 2 LAST $XR0 207 
J 0
(3164 1025);
DISPLAY 0.638298 (3164 1025);
PAINT MONO (3164 1025);
FORCEPROP 2 LAST CDS_LIB standard
J 0
(2950 1025);
DISPLAY INVISIBLE (2950 1025);
FORCEPROP 1 LAST OFFPAGE TRUE
J 0
(3275 900);
DISPLAY 0.872340 (3275 900);
PAINT GREEN (3275 900);
DISPLAY INVISIBLE (3275 900);
FORCEPROP 1 LAST COMMENT_BODY TRUE
J 0
(2900 925);
DISPLAY 0.872340 (2900 925);
PAINT GREEN (2900 925);
DISPLAY INVISIBLE (2900 925);
FORCEPROP 2 LAST PATH I190
J 0
(3150 1100);
DISPLAY 0.680851 (3150 1100);
DISPLAY INVISIBLE (3150 1100);
FORCEADD OFFPAGE..2
(2950 1125);
FORCEPROP 2 LAST $XR0 207 
J 0
(3139 1125);
DISPLAY 0.638298 (3139 1125);
PAINT MONO (3139 1125);
FORCEPROP 2 LAST CDS_LIB standard
J 0
(2950 1125);
DISPLAY INVISIBLE (2950 1125);
FORCEPROP 1 LAST OFFPAGE TRUE
J 0
(3275 1000);
DISPLAY 0.872340 (3275 1000);
PAINT GREEN (3275 1000);
DISPLAY INVISIBLE (3275 1000);
FORCEPROP 1 LAST COMMENT_BODY TRUE
J 0
(2905 1030);
DISPLAY 0.872340 (2905 1030);
PAINT GREEN (2905 1030);
DISPLAY INVISIBLE (2905 1030);
FORCEPROP 2 LAST PATH I191
J 0
(3125 1200);
DISPLAY 0.680851 (3125 1200);
DISPLAY INVISIBLE (3125 1200);
FORCEADD OFFPAGE..2
(3625 5525);
FORCEPROP 2 LAST $XR0 185 
J 0
(3814 5525);
DISPLAY 0.638298 (3814 5525);
PAINT MONO (3814 5525);
FORCEPROP 2 LAST CDS_LIB standard
J 0
(3625 5525);
DISPLAY INVISIBLE (3625 5525);
FORCEPROP 1 LAST OFFPAGE TRUE
J 0
(3950 5400);
DISPLAY 1.170213 (3950 5400);
PAINT GREEN (3950 5400);
DISPLAY INVISIBLE (3950 5400);
FORCEPROP 1 LAST COMMENT_BODY TRUE
J 0
(3580 5430);
DISPLAY 1.170213 (3580 5430);
PAINT GREEN (3580 5430);
DISPLAY INVISIBLE (3580 5430);
FORCEPROP 2 LAST PATH I194
J 0
(3800 5600);
DISPLAY 0.680851 (3800 5600);
DISPLAY INVISIBLE (3800 5600);
FORCEADD OFFPAGE..3
(3625 5475);
FORCEPROP 2 LAST $XR0 185 
J 0
(3839 5475);
DISPLAY 0.638298 (3839 5475);
PAINT MONO (3839 5475);
FORCEPROP 2 LAST CDS_LIB standard
J 0
(3625 5475);
DISPLAY INVISIBLE (3625 5475);
FORCEPROP 1 LAST OFFPAGE TRUE
J 0
(3950 5350);
DISPLAY 0.872340 (3950 5350);
DISPLAY INVISIBLE (3950 5350);
FORCEPROP 1 LAST COMMENT_BODY TRUE
J 0
(3575 5375);
DISPLAY 0.872340 (3575 5375);
PAINT GREEN (3575 5375);
DISPLAY INVISIBLE (3575 5375);
FORCEPROP 2 LAST PATH I195
J 0
(3825 5550);
DISPLAY 0.680851 (3825 5550);
DISPLAY INVISIBLE (3825 5550);
FORCEADD Q_RES..1
R 2
(3375 6500);
FORCEPROP 1 LAST LOCATION R6784
J 2
(3250 6500);
DISPLAY 0.617021 (3250 6500);
PAINT SKYBLUE (3250 6500);
FORCEPROP 0 LAST $SEC 1
J 0
(3250 6550);
DISPLAY 0.680851 (3250 6550);
PAINT MONO (3250 6550);
DISPLAY INVISIBLE (3250 6550);
FORCEPROP 0 LAST CDS_SEC 1
J 0
(3250 6550);
DISPLAY 0.680851 (3250 6550);
DISPLAY INVISIBLE (3250 6550);
FORCEPROP 1 LASTPIN (3475 6500) $PN 1
J 2
(3463 6512);
DISPLAY 0.787234 (3463 6512);
PAINT MONO (3463 6512);
FORCEPROP 1 LASTPIN (3275 6500) $PN 2
J 2
(3313 6512);
DISPLAY 0.787234 (3313 6512);
PAINT MONO (3313 6512);
FORCEPROP 1 LAST VALUE 0
J 0
(3475 6500);
DISPLAY 0.489362 (3475 6500);
PAINT SKYBLUE (3475 6500);
FORCEPROP 1 LAST MATERIAL CHIP
J 2
(3650 6500);
DISPLAY 0.489362 (3650 6500);
PAINT SKYBLUE (3650 6500);
FORCEPROP 1 LAST WATTAGE 1/16W
J 0
(2975 6425);
DISPLAY 0.489362 (2975 6425);
PAINT SKYBLUE (2975 6425);
DISPLAY INVISIBLE (2975 6425);
FORCEPROP 1 LAST TOLERANCE 5%
J 2
(3400 6425);
DISPLAY 0.489362 (3400 6425);
PAINT SKYBLUE (3400 6425);
DISPLAY INVISIBLE (3400 6425);
FORCEPROP 1 LAST PACK_TYPE 0402LF
J 2
(3325 6425);
DISPLAY 0.489362 (3325 6425);
PAINT SKYBLUE (3325 6425);
DISPLAY INVISIBLE (3325 6425);
FORCEPROP 2 LAST CDS_LIB pure_quanta
J 0
(3375 6500);
DISPLAY INVISIBLE (3375 6500);
FORCEPROP 1 LAST PART_NUMBER CS00002JB13
J 2
(3350 6550);
DISPLAY 0.489362 (3350 6550);
PAINT SKYBLUE (3350 6550);
DISPLAY INVISIBLE (3350 6550);
FORCEPROP 1 LAST PATH I198
J 2
(3425 6650);
DISPLAY 0.978723 (3425 6650);
PAINT WHITE (3425 6650);
DISPLAY INVISIBLE (3425 6650);
FORCEADD Q_RES..1
R 2
(3375 6450);
FORCEPROP 1 LAST LOCATION R6785
J 2
(3250 6450);
DISPLAY 0.617021 (3250 6450);
PAINT SKYBLUE (3250 6450);
FORCEPROP 0 LAST $SEC 1
J 0
(3250 6500);
DISPLAY 0.680851 (3250 6500);
PAINT MONO (3250 6500);
DISPLAY INVISIBLE (3250 6500);
FORCEPROP 0 LAST CDS_SEC 1
J 0
(3250 6500);
DISPLAY 0.680851 (3250 6500);
DISPLAY INVISIBLE (3250 6500);
FORCEPROP 1 LASTPIN (3475 6450) $PN 1
J 2
(3463 6462);
DISPLAY 0.787234 (3463 6462);
PAINT MONO (3463 6462);
FORCEPROP 1 LASTPIN (3275 6450) $PN 2
J 2
(3313 6462);
DISPLAY 0.787234 (3313 6462);
PAINT MONO (3313 6462);
FORCEPROP 1 LAST MATERIAL CHIP
J 2
(3650 6450);
DISPLAY 0.489362 (3650 6450);
PAINT SKYBLUE (3650 6450);
FORCEPROP 1 LAST VALUE 0
J 0
(3475 6450);
DISPLAY 0.489362 (3475 6450);
PAINT SKYBLUE (3475 6450);
FORCEPROP 1 LAST WATTAGE 1/16W
J 0
(2975 6375);
DISPLAY 0.489362 (2975 6375);
PAINT SKYBLUE (2975 6375);
DISPLAY INVISIBLE (2975 6375);
FORCEPROP 1 LAST TOLERANCE 5%
J 2
(3400 6375);
DISPLAY 0.489362 (3400 6375);
PAINT SKYBLUE (3400 6375);
DISPLAY INVISIBLE (3400 6375);
FORCEPROP 1 LAST PACK_TYPE 0402LF
J 2
(3325 6375);
DISPLAY 0.489362 (3325 6375);
PAINT SKYBLUE (3325 6375);
DISPLAY INVISIBLE (3325 6375);
FORCEPROP 2 LAST CDS_LIB pure_quanta
J 0
(3375 6450);
DISPLAY INVISIBLE (3375 6450);
FORCEPROP 1 LAST PART_NUMBER CS00002JB13
J 2
(3350 6500);
DISPLAY 0.489362 (3350 6500);
PAINT SKYBLUE (3350 6500);
DISPLAY INVISIBLE (3350 6500);
FORCEPROP 1 LAST PATH I199
J 2
(3425 6600);
DISPLAY 0.978723 (3425 6600);
PAINT WHITE (3425 6600);
DISPLAY INVISIBLE (3425 6600);
FORCEADD Q_RES..1
(-2100 5400);
FORCEPROP 1 LAST LOCATION R6024
J 0
(-2350 5400);
DISPLAY 0.489362 (-2350 5400);
PAINT SKYBLUE (-2350 5400);
FORCEPROP 0 LAST $SEC 1
J 0
(-2225 5450);
DISPLAY 0.680851 (-2225 5450);
PAINT MONO (-2225 5450);
DISPLAY INVISIBLE (-2225 5450);
FORCEPROP 0 LAST CDS_SEC 1
J 0
(-2225 5450);
DISPLAY 0.680851 (-2225 5450);
DISPLAY INVISIBLE (-2225 5450);
FORCEPROP 1 LASTPIN (-2200 5400) $PN 1
J 0
(-2188 5412);
DISPLAY 0.489362 (-2188 5412);
PAINT MONO (-2188 5412);
FORCEPROP 1 LASTPIN (-2000 5400) $PN 2
J 0
(-2038 5412);
DISPLAY 0.489362 (-2038 5412);
PAINT MONO (-2038 5412);
FORCEPROP 1 LAST VALUE 4.7K
J 0
(-1975 5400);
DISPLAY 0.489362 (-1975 5400);
PAINT SKYBLUE (-1975 5400);
FORCEPROP 1 LAST MATERIAL EMPTY
J 0
(-2000 5375);
DISPLAY 0.489362 (-2000 5375);
PAINT SKYBLUE (-2000 5375);
FORCEPROP 1 LAST PACK_TYPE 0402LF
J 0
(-1850 5250);
DISPLAY 0.510638 (-1850 5250);
PAINT SKYBLUE (-1850 5250);
DISPLAY INVISIBLE (-1850 5250);
FORCEPROP 1 LAST TOLERANCE 5%
J 0
(-1975 5400);
DISPLAY 0.510638 (-1975 5400);
PAINT SKYBLUE (-1975 5400);
DISPLAY INVISIBLE (-1975 5400);
FORCEPROP 1 LAST WATTAGE 1/16W
J 2
(-2125 5250);
DISPLAY 0.510638 (-2125 5250);
PAINT SKYBLUE (-2125 5250);
DISPLAY INVISIBLE (-2125 5250);
FORCEPROP 2 LAST CDS_LIB pure_quanta
J 0
(-2100 5400);
DISPLAY INVISIBLE (-2100 5400);
FORCEPROP 1 LAST PART_NUMBER CS24702JB10
J 0
(-2150 5500);
DISPLAY 0.510638 (-2150 5500);
PAINT SKYBLUE (-2150 5500);
DISPLAY INVISIBLE (-2150 5500);
FORCEPROP 1 LAST PATH I20
J 0
(-2150 5550);
DISPLAY 0.978723 (-2150 5550);
PAINT WHITE (-2150 5550);
DISPLAY INVISIBLE (-2150 5550);
FORCEADD OFFPAGE..2
(4950 6500);
FORCEPROP 2 LAST $XR0 184 
J 0
(5139 6500);
DISPLAY 0.638298 (5139 6500);
PAINT MONO (5139 6500);
FORCEPROP 2 LAST CDS_LIB standard
J 0
(4950 6500);
DISPLAY INVISIBLE (4950 6500);
FORCEPROP 1 LAST OFFPAGE TRUE
J 0
(5275 6375);
DISPLAY 1.170213 (5275 6375);
PAINT GREEN (5275 6375);
DISPLAY INVISIBLE (5275 6375);
FORCEPROP 1 LAST COMMENT_BODY TRUE
J 0
(4905 6405);
DISPLAY 1.170213 (4905 6405);
PAINT GREEN (4905 6405);
DISPLAY INVISIBLE (4905 6405);
FORCEPROP 2 LAST PATH I200
J 0
(5125 6575);
DISPLAY 0.680851 (5125 6575);
DISPLAY INVISIBLE (5125 6575);
FORCEADD OFFPAGE..3
(4950 6450);
FORCEPROP 2 LAST $XR0 184 
J 0
(5164 6450);
DISPLAY 0.638298 (5164 6450);
PAINT MONO (5164 6450);
FORCEPROP 2 LAST CDS_LIB standard
J 0
(4950 6450);
DISPLAY INVISIBLE (4950 6450);
FORCEPROP 1 LAST OFFPAGE TRUE
J 0
(5275 6325);
DISPLAY 0.872340 (5275 6325);
DISPLAY INVISIBLE (5275 6325);
FORCEPROP 1 LAST COMMENT_BODY TRUE
J 0
(4900 6350);
DISPLAY 0.872340 (4900 6350);
PAINT GREEN (4900 6350);
DISPLAY INVISIBLE (4900 6350);
FORCEPROP 2 LAST PATH I201
J 0
(5150 6525);
DISPLAY 0.680851 (5150 6525);
DISPLAY INVISIBLE (5150 6525);
FORCEADD OFFPAGE..3
(3850 750);
FORCEPROP 2 LAST $XR0 363 
J 0
(4064 750);
DISPLAY 0.638298 (4064 750);
PAINT MONO (4064 750);
FORCEPROP 2 LAST CDS_LIB standard
J 0
(3850 750);
DISPLAY INVISIBLE (3850 750);
FORCEPROP 1 LAST OFFPAGE TRUE
J 0
(4175 625);
DISPLAY 0.872340 (4175 625);
PAINT GREEN (4175 625);
DISPLAY INVISIBLE (4175 625);
FORCEPROP 1 LAST COMMENT_BODY TRUE
J 0
(3800 650);
DISPLAY 0.872340 (3800 650);
PAINT GREEN (3800 650);
DISPLAY INVISIBLE (3800 650);
FORCEPROP 2 LAST PATH I204
J 0
(4050 825);
DISPLAY 0.680851 (4050 825);
DISPLAY INVISIBLE (4050 825);
FORCEADD OFFPAGE..2
(3850 850);
FORCEPROP 2 LAST $XR0 363 
J 0
(4039 850);
DISPLAY 0.638298 (4039 850);
PAINT MONO (4039 850);
FORCEPROP 2 LAST CDS_LIB standard
J 0
(3850 850);
DISPLAY INVISIBLE (3850 850);
FORCEPROP 1 LAST OFFPAGE TRUE
J 0
(4175 725);
DISPLAY 0.872340 (4175 725);
PAINT GREEN (4175 725);
DISPLAY INVISIBLE (4175 725);
FORCEPROP 1 LAST COMMENT_BODY TRUE
J 0
(3805 755);
DISPLAY 0.872340 (3805 755);
PAINT GREEN (3805 755);
DISPLAY INVISIBLE (3805 755);
FORCEPROP 2 LAST PATH I205
J 0
(4025 925);
DISPLAY 0.680851 (4025 925);
DISPLAY INVISIBLE (4025 925);
FORCEADD Q_RES..1
(-125 2625);
FORCEPROP 1 LAST LOCATION R6859
J 0
(0 2625);
DISPLAY 0.489362 (0 2625);
PAINT SKYBLUE (0 2625);
FORCEPROP 0 LAST $SEC 1
J 0
(-250 2675);
DISPLAY 0.680851 (-250 2675);
PAINT MONO (-250 2675);
DISPLAY INVISIBLE (-250 2675);
FORCEPROP 0 LAST CDS_SEC 1
J 0
(-250 2675);
DISPLAY 0.680851 (-250 2675);
DISPLAY INVISIBLE (-250 2675);
FORCEPROP 1 LASTPIN (-225 2625) $PN 1
J 0
(-213 2637);
DISPLAY 0.787234 (-213 2637);
PAINT MONO (-213 2637);
FORCEPROP 1 LASTPIN (-25 2625) $PN 2
J 0
(-63 2637);
DISPLAY 0.787234 (-63 2637);
PAINT MONO (-63 2637);
FORCEPROP 1 LAST VALUE 0
J 2
(-250 2650);
DISPLAY 0.489362 (-250 2650);
PAINT SKYBLUE (-250 2650);
FORCEPROP 1 LAST WATTAGE 1/16W
J 0
(-25 2575);
DISPLAY 0.489362 (-25 2575);
PAINT SKYBLUE (-25 2575);
DISPLAY INVISIBLE (-25 2575);
FORCEPROP 1 LAST MATERIAL CHIP
J 0
(-375 2550);
DISPLAY 0.489362 (-375 2550);
PAINT SKYBLUE (-375 2550);
DISPLAY INVISIBLE (-375 2550);
FORCEPROP 1 LAST TOLERANCE 5%
J 0
(0 2650);
DISPLAY 0.489362 (0 2650);
PAINT SKYBLUE (0 2650);
DISPLAY INVISIBLE (0 2650);
FORCEPROP 1 LAST PACK_TYPE 0402LF
J 0
(-25 2550);
DISPLAY 0.489362 (-25 2550);
PAINT SKYBLUE (-25 2550);
DISPLAY INVISIBLE (-25 2550);
FORCEPROP 2 LAST CDS_LIB pure_quanta
J 0
(-125 2625);
DISPLAY INVISIBLE (-125 2625);
FORCEPROP 1 LAST PART_NUMBER CS00002JB13
J 0
(-375 2575);
DISPLAY 0.489362 (-375 2575);
PAINT SKYBLUE (-375 2575);
DISPLAY INVISIBLE (-375 2575);
FORCEPROP 1 LAST PATH I206
J 0
(-175 2775);
DISPLAY 0.978723 (-175 2775);
PAINT WHITE (-175 2775);
DISPLAY INVISIBLE (-175 2775);
FORCEADD Q_RES..1
(-125 2525);
FORCEPROP 1 LAST LOCATION R6858
J 0
(0 2525);
DISPLAY 0.489362 (0 2525);
PAINT SKYBLUE (0 2525);
FORCEPROP 0 LAST $SEC 1
J 0
(-250 2575);
DISPLAY 0.680851 (-250 2575);
PAINT MONO (-250 2575);
DISPLAY INVISIBLE (-250 2575);
FORCEPROP 0 LAST CDS_SEC 1
J 0
(-250 2575);
DISPLAY 0.680851 (-250 2575);
DISPLAY INVISIBLE (-250 2575);
FORCEPROP 1 LASTPIN (-225 2525) $PN 1
J 0
(-213 2537);
DISPLAY 0.787234 (-213 2537);
PAINT MONO (-213 2537);
FORCEPROP 1 LASTPIN (-25 2525) $PN 2
J 0
(-63 2537);
DISPLAY 0.787234 (-63 2537);
PAINT MONO (-63 2537);
FORCEPROP 1 LAST VALUE 0
J 2
(-250 2550);
DISPLAY 0.489362 (-250 2550);
PAINT SKYBLUE (-250 2550);
FORCEPROP 2 LAST CDS_LIB pure_quanta
J 0
(-125 2525);
DISPLAY INVISIBLE (-125 2525);
FORCEPROP 1 LAST PACK_TYPE 0402LF
J 0
(-25 2450);
DISPLAY 0.489362 (-25 2450);
PAINT SKYBLUE (-25 2450);
DISPLAY INVISIBLE (-25 2450);
FORCEPROP 1 LAST TOLERANCE 5%
J 0
(0 2550);
DISPLAY 0.489362 (0 2550);
PAINT SKYBLUE (0 2550);
DISPLAY INVISIBLE (0 2550);
FORCEPROP 1 LAST MATERIAL CHIP
J 0
(-375 2450);
DISPLAY 0.489362 (-375 2450);
PAINT SKYBLUE (-375 2450);
DISPLAY INVISIBLE (-375 2450);
FORCEPROP 1 LAST WATTAGE 1/16W
J 0
(-25 2475);
DISPLAY 0.489362 (-25 2475);
PAINT SKYBLUE (-25 2475);
DISPLAY INVISIBLE (-25 2475);
FORCEPROP 1 LAST PART_NUMBER CS00002JB13
J 0
(-375 2475);
DISPLAY 0.489362 (-375 2475);
PAINT SKYBLUE (-375 2475);
DISPLAY INVISIBLE (-375 2475);
FORCEPROP 1 LAST PATH I207
J 0
(-175 2675);
DISPLAY 0.978723 (-175 2675);
PAINT WHITE (-175 2675);
DISPLAY INVISIBLE (-175 2675);
FORCEADD OFFPAGE..2
(850 2525);
FORCEPROP 2 LAST $XR0 365 
J 0
(1039 2525);
DISPLAY 0.638298 (1039 2525);
PAINT MONO (1039 2525);
FORCEPROP 2 LAST CDS_LIB standard
J 0
(850 2525);
DISPLAY INVISIBLE (850 2525);
FORCEPROP 1 LAST OFFPAGE TRUE
J 0
(1175 2400);
DISPLAY 0.872340 (1175 2400);
PAINT GREEN (1175 2400);
DISPLAY INVISIBLE (1175 2400);
FORCEPROP 1 LAST COMMENT_BODY TRUE
J 0
(805 2430);
DISPLAY 0.872340 (805 2430);
PAINT GREEN (805 2430);
DISPLAY INVISIBLE (805 2430);
FORCEPROP 2 LAST PATH I208
J 0
(1025 2600);
DISPLAY 0.680851 (1025 2600);
DISPLAY INVISIBLE (1025 2600);
FORCEADD OFFPAGE..3
(850 2625);
FORCEPROP 2 LAST $XR0 365 
J 0
(1064 2625);
DISPLAY 0.638298 (1064 2625);
PAINT MONO (1064 2625);
FORCEPROP 2 LAST CDS_LIB standard
J 0
(850 2625);
DISPLAY INVISIBLE (850 2625);
FORCEPROP 1 LAST OFFPAGE TRUE
J 0
(1175 2500);
DISPLAY 0.872340 (1175 2500);
PAINT GREEN (1175 2500);
DISPLAY INVISIBLE (1175 2500);
FORCEPROP 1 LAST COMMENT_BODY TRUE
J 0
(800 2525);
DISPLAY 0.872340 (800 2525);
PAINT GREEN (800 2525);
DISPLAY INVISIBLE (800 2525);
FORCEPROP 2 LAST PATH I209
J 0
(1050 2700);
DISPLAY 0.680851 (1050 2700);
DISPLAY INVISIBLE (1050 2700);
FORCEADD Q_RES..1
(-2100 5450);
FORCEPROP 1 LAST LOCATION R6023
J 0
(-2350 5450);
DISPLAY 0.489362 (-2350 5450);
PAINT SKYBLUE (-2350 5450);
FORCEPROP 0 LAST $SEC 1
J 0
(-2250 5500);
DISPLAY 0.680851 (-2250 5500);
PAINT MONO (-2250 5500);
DISPLAY INVISIBLE (-2250 5500);
FORCEPROP 0 LAST CDS_SEC 1
J 0
(-2250 5500);
DISPLAY 0.680851 (-2250 5500);
DISPLAY INVISIBLE (-2250 5500);
FORCEPROP 1 LASTPIN (-2200 5450) $PN 1
J 0
(-2188 5462);
DISPLAY 0.489362 (-2188 5462);
PAINT MONO (-2188 5462);
FORCEPROP 1 LASTPIN (-2000 5450) $PN 2
J 0
(-2038 5462);
DISPLAY 0.489362 (-2038 5462);
PAINT MONO (-2038 5462);
FORCEPROP 1 LAST MATERIAL EMPTY
J 0
(-2150 5475);
DISPLAY 0.489362 (-2150 5475);
PAINT SKYBLUE (-2150 5475);
FORCEPROP 1 LAST VALUE 2K
J 0
(-1975 5450);
DISPLAY 0.489362 (-1975 5450);
PAINT SKYBLUE (-1975 5450);
FORCEPROP 2 LAST CDS_LIB pure_quanta
J 0
(-2100 5450);
DISPLAY INVISIBLE (-2100 5450);
FORCEPROP 1 LAST WATTAGE 1/16W
J 2
(-2125 5300);
DISPLAY 0.510638 (-2125 5300);
PAINT SKYBLUE (-2125 5300);
DISPLAY INVISIBLE (-2125 5300);
FORCEPROP 1 LAST TOLERANCE 5%
J 0
(-1975 5450);
DISPLAY 0.510638 (-1975 5450);
PAINT SKYBLUE (-1975 5450);
DISPLAY INVISIBLE (-1975 5450);
FORCEPROP 1 LAST PACK_TYPE 0402LF
J 0
(-1850 5300);
DISPLAY 0.510638 (-1850 5300);
PAINT SKYBLUE (-1850 5300);
DISPLAY INVISIBLE (-1850 5300);
FORCEPROP 1 LAST PART_NUMBER TMP_QCS22002JB29
J 0
(-2150 5550);
DISPLAY 0.510638 (-2150 5550);
PAINT SKYBLUE (-2150 5550);
DISPLAY INVISIBLE (-2150 5550);
FORCEPROP 1 LAST PATH I21
J 0
(-2150 5600);
DISPLAY 0.978723 (-2150 5600);
PAINT WHITE (-2150 5600);
DISPLAY INVISIBLE (-2150 5600);
FORCEADD OFFPAGE..2
(2250 5175);
FORCEPROP 2 LAST $XR0 183 
J 0
(2439 5175);
DISPLAY 0.638298 (2439 5175);
PAINT MONO (2439 5175);
FORCEPROP 2 LAST CDS_LIB standard
J 0
(2250 5175);
DISPLAY INVISIBLE (2250 5175);
FORCEPROP 1 LAST OFFPAGE TRUE
J 0
(2575 5050);
DISPLAY 1.170213 (2575 5050);
PAINT GREEN (2575 5050);
DISPLAY INVISIBLE (2575 5050);
FORCEPROP 1 LAST COMMENT_BODY TRUE
J 0
(2205 5080);
DISPLAY 1.170213 (2205 5080);
PAINT GREEN (2205 5080);
DISPLAY INVISIBLE (2205 5080);
FORCEPROP 2 LAST PATH I212
J 0
(2425 5250);
DISPLAY 0.680851 (2425 5250);
DISPLAY INVISIBLE (2425 5250);
FORCEADD OFFPAGE..3
(2250 5100);
FORCEPROP 2 LAST $XR0 183 
J 0
(2464 5100);
DISPLAY 0.638298 (2464 5100);
PAINT MONO (2464 5100);
FORCEPROP 2 LAST CDS_LIB standard
J 0
(2250 5100);
DISPLAY INVISIBLE (2250 5100);
FORCEPROP 1 LAST OFFPAGE TRUE
J 0
(2575 4975);
DISPLAY 0.872340 (2575 4975);
DISPLAY INVISIBLE (2575 4975);
FORCEPROP 1 LAST COMMENT_BODY TRUE
J 0
(2200 5000);
DISPLAY 0.872340 (2200 5000);
PAINT GREEN (2200 5000);
DISPLAY INVISIBLE (2200 5000);
FORCEPROP 2 LAST PATH I213
J 0
(2450 5175);
DISPLAY 0.680851 (2450 5175);
DISPLAY INVISIBLE (2450 5175);
FORCEADD OFFPAGE..2
(2250 4975);
FORCEPROP 2 LAST $XR0 182 
J 0
(2439 4975);
DISPLAY 0.638298 (2439 4975);
PAINT MONO (2439 4975);
FORCEPROP 2 LAST CDS_LIB standard
J 0
(2250 4975);
DISPLAY INVISIBLE (2250 4975);
FORCEPROP 1 LAST OFFPAGE TRUE
J 0
(2575 4850);
DISPLAY 1.170213 (2575 4850);
PAINT GREEN (2575 4850);
DISPLAY INVISIBLE (2575 4850);
FORCEPROP 1 LAST COMMENT_BODY TRUE
J 0
(2205 4880);
DISPLAY 1.170213 (2205 4880);
PAINT GREEN (2205 4880);
DISPLAY INVISIBLE (2205 4880);
FORCEPROP 2 LAST PATH I214
J 0
(2425 5050);
DISPLAY 0.680851 (2425 5050);
DISPLAY INVISIBLE (2425 5050);
FORCEADD OFFPAGE..3
(2250 4900);
FORCEPROP 2 LAST $XR0 182 
J 0
(2464 4900);
DISPLAY 0.638298 (2464 4900);
PAINT MONO (2464 4900);
FORCEPROP 2 LAST CDS_LIB standard
J 0
(2250 4900);
DISPLAY INVISIBLE (2250 4900);
FORCEPROP 1 LAST OFFPAGE TRUE
J 0
(2575 4775);
DISPLAY 0.872340 (2575 4775);
DISPLAY INVISIBLE (2575 4775);
FORCEPROP 1 LAST COMMENT_BODY TRUE
J 0
(2200 4800);
DISPLAY 0.872340 (2200 4800);
PAINT GREEN (2200 4800);
DISPLAY INVISIBLE (2200 4800);
FORCEPROP 2 LAST PATH I215
J 0
(2450 4975);
DISPLAY 0.680851 (2450 4975);
DISPLAY INVISIBLE (2450 4975);
FORCEADD Q_RES..1
(1425 5175);
FORCEPROP 1 LAST LOCATION R6862
J 0
(1375 5200);
DISPLAY 0.617021 (1375 5200);
PAINT SKYBLUE (1375 5200);
FORCEPROP 0 LAST $SEC 1
J 0
(1375 5250);
DISPLAY 0.680851 (1375 5250);
PAINT MONO (1375 5250);
DISPLAY INVISIBLE (1375 5250);
FORCEPROP 0 LAST CDS_SEC 1
J 0
(1375 5250);
DISPLAY 0.680851 (1375 5250);
DISPLAY INVISIBLE (1375 5250);
FORCEPROP 1 LASTPIN (1325 5175) $PN 1
J 0
(1337 5187);
DISPLAY 0.787234 (1337 5187);
PAINT MONO (1337 5187);
FORCEPROP 1 LASTPIN (1525 5175) $PN 2
J 0
(1487 5187);
DISPLAY 0.787234 (1487 5187);
PAINT MONO (1487 5187);
FORCEPROP 1 LAST MATERIAL CHIP
J 0
(1650 5175);
DISPLAY 0.489362 (1650 5175);
PAINT SKYBLUE (1650 5175);
FORCEPROP 1 LAST VALUE 33
J 2
(1625 5175);
DISPLAY 0.617021 (1625 5175);
PAINT SKYBLUE (1625 5175);
FORCEPROP 2 LAST CDS_LIB pure_quanta
J 0
(1425 5175);
DISPLAY INVISIBLE (1425 5175);
FORCEPROP 1 LAST WATTAGE 1/16W
J 2
(1825 5100);
DISPLAY 0.489362 (1825 5100);
PAINT SKYBLUE (1825 5100);
DISPLAY INVISIBLE (1825 5100);
FORCEPROP 1 LAST TOLERANCE 5%
J 0
(1400 5100);
DISPLAY 0.489362 (1400 5100);
PAINT SKYBLUE (1400 5100);
DISPLAY INVISIBLE (1400 5100);
FORCEPROP 1 LAST PACK_TYPE 0402LF
J 0
(1475 5100);
DISPLAY 0.489362 (1475 5100);
PAINT SKYBLUE (1475 5100);
DISPLAY INVISIBLE (1475 5100);
FORCEPROP 1 LAST PART_NUMBER CS03302JB10
J 0
(1450 5225);
DISPLAY 0.489362 (1450 5225);
PAINT SKYBLUE (1450 5225);
DISPLAY INVISIBLE (1450 5225);
FORCEPROP 1 LAST PATH I218
J 0
(1375 5325);
DISPLAY 0.978723 (1375 5325);
PAINT WHITE (1375 5325);
DISPLAY INVISIBLE (1375 5325);
FORCEADD Q_RES..1
(1425 5100);
FORCEPROP 1 LAST LOCATION R6863
J 0
(1375 5125);
DISPLAY 0.617021 (1375 5125);
PAINT SKYBLUE (1375 5125);
FORCEPROP 0 LAST $SEC 1
J 0
(1375 5175);
DISPLAY 0.680851 (1375 5175);
PAINT MONO (1375 5175);
DISPLAY INVISIBLE (1375 5175);
FORCEPROP 0 LAST CDS_SEC 1
J 0
(1375 5175);
DISPLAY 0.680851 (1375 5175);
DISPLAY INVISIBLE (1375 5175);
FORCEPROP 1 LASTPIN (1325 5100) $PN 1
J 0
(1337 5112);
DISPLAY 0.787234 (1337 5112);
PAINT MONO (1337 5112);
FORCEPROP 1 LASTPIN (1525 5100) $PN 2
J 0
(1487 5112);
DISPLAY 0.787234 (1487 5112);
PAINT MONO (1487 5112);
FORCEPROP 1 LAST MATERIAL CHIP
J 0
(1650 5100);
DISPLAY 0.489362 (1650 5100);
PAINT SKYBLUE (1650 5100);
FORCEPROP 1 LAST VALUE 33
J 2
(1625 5100);
DISPLAY 0.617021 (1625 5100);
PAINT SKYBLUE (1625 5100);
FORCEPROP 2 LAST CDS_LIB pure_quanta
J 0
(1425 5100);
DISPLAY INVISIBLE (1425 5100);
FORCEPROP 1 LAST PACK_TYPE 0402LF
J 0
(1475 5025);
DISPLAY 0.489362 (1475 5025);
PAINT SKYBLUE (1475 5025);
DISPLAY INVISIBLE (1475 5025);
FORCEPROP 1 LAST TOLERANCE 5%
J 0
(1400 5025);
DISPLAY 0.489362 (1400 5025);
PAINT SKYBLUE (1400 5025);
DISPLAY INVISIBLE (1400 5025);
FORCEPROP 1 LAST WATTAGE 1/16W
J 2
(1825 5025);
DISPLAY 0.489362 (1825 5025);
PAINT SKYBLUE (1825 5025);
DISPLAY INVISIBLE (1825 5025);
FORCEPROP 1 LAST PART_NUMBER CS03302JB10
J 0
(1450 5150);
DISPLAY 0.489362 (1450 5150);
PAINT SKYBLUE (1450 5150);
DISPLAY INVISIBLE (1450 5150);
FORCEPROP 1 LAST PATH I219
J 0
(1375 5250);
DISPLAY 0.978723 (1375 5250);
PAINT WHITE (1375 5250);
DISPLAY INVISIBLE (1375 5250);
FORCEADD Q_RES..1
(-2100 5550);
FORCEPROP 1 LAST LOCATION R6021
J 0
(-2350 5550);
DISPLAY 0.489362 (-2350 5550);
PAINT SKYBLUE (-2350 5550);
FORCEPROP 0 LAST $SEC 1
J 0
(-2250 5600);
DISPLAY 0.680851 (-2250 5600);
PAINT MONO (-2250 5600);
DISPLAY INVISIBLE (-2250 5600);
FORCEPROP 0 LAST CDS_SEC 1
J 0
(-2250 5600);
DISPLAY 0.680851 (-2250 5600);
DISPLAY INVISIBLE (-2250 5600);
FORCEPROP 1 LASTPIN (-2200 5550) $PN 1
J 0
(-2188 5562);
DISPLAY 0.489362 (-2188 5562);
PAINT MONO (-2188 5562);
FORCEPROP 1 LASTPIN (-2000 5550) $PN 2
J 0
(-2038 5562);
DISPLAY 0.489362 (-2038 5562);
PAINT MONO (-2038 5562);
FORCEPROP 1 LAST VALUE 2K
J 0
(-1975 5550);
DISPLAY 0.489362 (-1975 5550);
PAINT SKYBLUE (-1975 5550);
FORCEPROP 1 LAST MATERIAL EMPTY
J 0
(-2000 5525);
DISPLAY 0.489362 (-2000 5525);
PAINT SKYBLUE (-2000 5525);
DISPLAY INVISIBLE (-2000 5525);
FORCEPROP 1 LAST PACK_TYPE 0402LF
J 0
(-1850 5400);
DISPLAY 0.510638 (-1850 5400);
PAINT SKYBLUE (-1850 5400);
DISPLAY INVISIBLE (-1850 5400);
FORCEPROP 1 LAST TOLERANCE 5%
J 0
(-1975 5550);
DISPLAY 0.510638 (-1975 5550);
PAINT SKYBLUE (-1975 5550);
DISPLAY INVISIBLE (-1975 5550);
FORCEPROP 1 LAST WATTAGE 1/16W
J 2
(-2125 5400);
DISPLAY 0.510638 (-2125 5400);
PAINT SKYBLUE (-2125 5400);
DISPLAY INVISIBLE (-2125 5400);
FORCEPROP 2 LAST CDS_LIB pure_quanta
J 0
(-2100 5550);
DISPLAY INVISIBLE (-2100 5550);
FORCEPROP 1 LAST PART_NUMBER TMP_QCS22002JB29
J 0
(-2150 5650);
DISPLAY 0.510638 (-2150 5650);
PAINT SKYBLUE (-2150 5650);
DISPLAY INVISIBLE (-2150 5650);
FORCEPROP 1 LAST PATH I22
J 0
(-2150 5700);
DISPLAY 0.978723 (-2150 5700);
PAINT WHITE (-2150 5700);
DISPLAY INVISIBLE (-2150 5700);
FORCEADD Q_RES..1
(1425 4975);
FORCEPROP 1 LAST LOCATION R6864
J 0
(1375 5000);
DISPLAY 0.617021 (1375 5000);
PAINT SKYBLUE (1375 5000);
FORCEPROP 0 LAST $SEC 1
J 0
(1375 5050);
DISPLAY 0.680851 (1375 5050);
PAINT MONO (1375 5050);
DISPLAY INVISIBLE (1375 5050);
FORCEPROP 0 LAST CDS_SEC 1
J 0
(1375 5050);
DISPLAY 0.680851 (1375 5050);
DISPLAY INVISIBLE (1375 5050);
FORCEPROP 1 LASTPIN (1325 4975) $PN 1
J 0
(1337 4987);
DISPLAY 0.787234 (1337 4987);
PAINT MONO (1337 4987);
FORCEPROP 1 LASTPIN (1525 4975) $PN 2
J 0
(1487 4987);
DISPLAY 0.787234 (1487 4987);
PAINT MONO (1487 4987);
FORCEPROP 1 LAST MATERIAL CHIP
J 0
(1650 4975);
DISPLAY 0.489362 (1650 4975);
PAINT SKYBLUE (1650 4975);
FORCEPROP 1 LAST VALUE 33
J 2
(1625 4975);
DISPLAY 0.617021 (1625 4975);
PAINT SKYBLUE (1625 4975);
FORCEPROP 2 LAST CDS_LIB pure_quanta
J 0
(1425 4975);
DISPLAY INVISIBLE (1425 4975);
FORCEPROP 1 LAST PACK_TYPE 0402LF
J 0
(1475 4900);
DISPLAY 0.489362 (1475 4900);
PAINT SKYBLUE (1475 4900);
DISPLAY INVISIBLE (1475 4900);
FORCEPROP 1 LAST TOLERANCE 5%
J 0
(1400 4900);
DISPLAY 0.489362 (1400 4900);
PAINT SKYBLUE (1400 4900);
DISPLAY INVISIBLE (1400 4900);
FORCEPROP 1 LAST WATTAGE 1/16W
J 2
(1825 4900);
DISPLAY 0.489362 (1825 4900);
PAINT SKYBLUE (1825 4900);
DISPLAY INVISIBLE (1825 4900);
FORCEPROP 1 LAST PART_NUMBER CS03302JB10
J 0
(1450 5025);
DISPLAY 0.489362 (1450 5025);
PAINT SKYBLUE (1450 5025);
DISPLAY INVISIBLE (1450 5025);
FORCEPROP 1 LAST PATH I220
J 0
(1375 5125);
DISPLAY 0.978723 (1375 5125);
PAINT WHITE (1375 5125);
DISPLAY INVISIBLE (1375 5125);
FORCEADD Q_RES..1
(1425 4900);
FORCEPROP 1 LAST LOCATION R6865
J 0
(1375 4925);
DISPLAY 0.617021 (1375 4925);
PAINT SKYBLUE (1375 4925);
FORCEPROP 0 LAST $SEC 1
J 0
(1375 4975);
DISPLAY 0.680851 (1375 4975);
PAINT MONO (1375 4975);
DISPLAY INVISIBLE (1375 4975);
FORCEPROP 0 LAST CDS_SEC 1
J 0
(1375 4975);
DISPLAY 0.680851 (1375 4975);
DISPLAY INVISIBLE (1375 4975);
FORCEPROP 1 LASTPIN (1325 4900) $PN 1
J 0
(1337 4912);
DISPLAY 0.787234 (1337 4912);
PAINT MONO (1337 4912);
FORCEPROP 1 LASTPIN (1525 4900) $PN 2
J 0
(1487 4912);
DISPLAY 0.787234 (1487 4912);
PAINT MONO (1487 4912);
FORCEPROP 1 LAST MATERIAL CHIP
J 0
(1650 4900);
DISPLAY 0.489362 (1650 4900);
PAINT SKYBLUE (1650 4900);
FORCEPROP 1 LAST VALUE 33
J 2
(1625 4900);
DISPLAY 0.617021 (1625 4900);
PAINT SKYBLUE (1625 4900);
FORCEPROP 2 LAST CDS_LIB pure_quanta
J 0
(1425 4900);
DISPLAY INVISIBLE (1425 4900);
FORCEPROP 1 LAST PACK_TYPE 0402LF
J 0
(1475 4825);
DISPLAY 0.489362 (1475 4825);
PAINT SKYBLUE (1475 4825);
DISPLAY INVISIBLE (1475 4825);
FORCEPROP 1 LAST TOLERANCE 5%
J 0
(1400 4825);
DISPLAY 0.489362 (1400 4825);
PAINT SKYBLUE (1400 4825);
DISPLAY INVISIBLE (1400 4825);
FORCEPROP 1 LAST WATTAGE 1/16W
J 2
(1825 4825);
DISPLAY 0.489362 (1825 4825);
PAINT SKYBLUE (1825 4825);
DISPLAY INVISIBLE (1825 4825);
FORCEPROP 1 LAST PART_NUMBER CS03302JB10
J 0
(1450 4950);
DISPLAY 0.489362 (1450 4950);
PAINT SKYBLUE (1450 4950);
DISPLAY INVISIBLE (1450 4950);
FORCEPROP 1 LAST PATH I221
J 0
(1375 5050);
DISPLAY 0.978723 (1375 5050);
PAINT WHITE (1375 5050);
DISPLAY INVISIBLE (1375 5050);
FORCEADD Q_RES..1
(600 5525);
FORCEPROP 1 LAST LOCATION R1516
J 0
(350 5525);
DISPLAY 0.638298 (350 5525);
FORCEPROP 0 LAST $SEC 1
J 0
(775 5675);
DISPLAY 0.680851 (775 5675);
PAINT MONO (775 5675);
DISPLAY INVISIBLE (775 5675);
FORCEPROP 0 LAST CDS_SEC 1
J 0
(775 5675);
DISPLAY 0.680851 (775 5675);
DISPLAY INVISIBLE (775 5675);
FORCEPROP 1 LASTPIN (500 5525) $PN 1
J 0
(512 5537);
DISPLAY 0.787234 (512 5537);
PAINT MONO (512 5537);
FORCEPROP 1 LASTPIN (700 5525) $PN 2
J 0
(662 5537);
DISPLAY 0.787234 (662 5537);
PAINT MONO (662 5537);
FORCEPROP 1 LAST WATTAGE 1/16W
J 2
(775 5650);
DISPLAY 0.510638 (775 5650);
FORCEPROP 1 LAST PACK_TYPE 0402LF
J 0
(475 5650);
DISPLAY 0.510638 (475 5650);
FORCEPROP 1 LAST MATERIAL CHIP
J 0
(900 5525);
DISPLAY 0.510638 (900 5525);
FORCEPROP 1 LAST TOLERANCE 1%
J 0
(825 5525);
DISPLAY 0.510638 (825 5525);
FORCEPROP 1 LAST VALUE 33.2
J 2
(800 5525);
DISPLAY 0.510638 (800 5525);
FORCEPROP 2 LAST CDS_LIB pure_quanta
J 0
(600 5525);
DISPLAY INVISIBLE (600 5525);
FORCEPROP 1 LAST PART_NUMBER CS03322FB03
J 0
(475 5600);
DISPLAY 0.510638 (475 5600);
DISPLAY INVISIBLE (475 5600);
FORCEPROP 1 LAST PATH I222
J 0
(550 5675);
DISPLAY 0.978723 (550 5675);
PAINT WHITE (550 5675);
DISPLAY INVISIBLE (550 5675);
FORCEADD Q_RES..1
(600 5475);
FORCEPROP 1 LAST LOCATION R1517
J 0
(350 5475);
DISPLAY 0.638298 (350 5475);
FORCEPROP 0 LAST $SEC 1
J 0
(350 5525);
DISPLAY 0.680851 (350 5525);
PAINT MONO (350 5525);
DISPLAY INVISIBLE (350 5525);
FORCEPROP 0 LAST CDS_SEC 1
J 0
(350 5525);
DISPLAY 0.680851 (350 5525);
DISPLAY INVISIBLE (350 5525);
FORCEPROP 1 LASTPIN (500 5475) $PN 1
J 0
(512 5487);
DISPLAY 0.787234 (512 5487);
PAINT MONO (512 5487);
FORCEPROP 1 LASTPIN (700 5475) $PN 2
J 0
(662 5487);
DISPLAY 0.787234 (662 5487);
PAINT MONO (662 5487);
FORCEPROP 1 LAST TOLERANCE 1%
J 0
(825 5475);
DISPLAY 0.510638 (825 5475);
FORCEPROP 1 LAST MATERIAL CHIP
J 0
(900 5475);
DISPLAY 0.510638 (900 5475);
FORCEPROP 1 LAST VALUE 33.2
J 2
(800 5475);
DISPLAY 0.510638 (800 5475);
FORCEPROP 1 LAST WATTAGE 1/16W
J 2
(800 5575);
DISPLAY 0.638298 (800 5575);
DISPLAY INVISIBLE (800 5575);
FORCEPROP 1 LAST PACK_TYPE 0402LF
J 0
(950 5475);
DISPLAY 0.638298 (950 5475);
DISPLAY INVISIBLE (950 5475);
FORCEPROP 2 LAST CDS_LIB pure_quanta
J 0
(600 5475);
DISPLAY INVISIBLE (600 5475);
FORCEPROP 1 LAST PART_NUMBER CS03322FB03
J 0
(475 5525);
DISPLAY 0.638298 (475 5525);
DISPLAY INVISIBLE (475 5525);
FORCEPROP 1 LAST PATH I223
J 0
(550 5625);
DISPLAY 0.978723 (550 5625);
PAINT WHITE (550 5625);
DISPLAY INVISIBLE (550 5625);
FORCEADD Q_RES..1
(-1625 2375);
FORCEPROP 1 LAST LOCATION R308
J 0
(-1900 2400);
DISPLAY 0.617021 (-1900 2400);
PAINT SKYBLUE (-1900 2400);
FORCEPROP 0 LAST $SEC 1
J 0
(-1900 2450);
DISPLAY 0.680851 (-1900 2450);
PAINT MONO (-1900 2450);
DISPLAY INVISIBLE (-1900 2450);
FORCEPROP 0 LAST CDS_SEC 1
J 0
(-1900 2450);
DISPLAY 0.680851 (-1900 2450);
DISPLAY INVISIBLE (-1900 2450);
FORCEPROP 1 LASTPIN (-1725 2375) $PN 1
J 0
(-1713 2387);
DISPLAY 0.787234 (-1713 2387);
PAINT MONO (-1713 2387);
FORCEPROP 1 LASTPIN (-1525 2375) $PN 2
J 0
(-1563 2387);
DISPLAY 0.787234 (-1563 2387);
PAINT MONO (-1563 2387);
FORCEPROP 1 LAST VALUE 33
J 2
(-1425 2375);
DISPLAY 0.617021 (-1425 2375);
PAINT SKYBLUE (-1425 2375);
FORCEPROP 1 LAST PACK_TYPE 0402LF
J 0
(-1575 2300);
DISPLAY 0.489362 (-1575 2300);
PAINT SKYBLUE (-1575 2300);
DISPLAY INVISIBLE (-1575 2300);
FORCEPROP 1 LAST TOLERANCE 5%
J 0
(-1650 2300);
DISPLAY 0.489362 (-1650 2300);
PAINT SKYBLUE (-1650 2300);
DISPLAY INVISIBLE (-1650 2300);
FORCEPROP 1 LAST MATERIAL CHIP
J 0
(-1200 2300);
DISPLAY 0.489362 (-1200 2300);
PAINT SKYBLUE (-1200 2300);
DISPLAY INVISIBLE (-1200 2300);
FORCEPROP 1 LAST WATTAGE 1/16W
J 2
(-1225 2300);
DISPLAY 0.489362 (-1225 2300);
PAINT SKYBLUE (-1225 2300);
DISPLAY INVISIBLE (-1225 2300);
FORCEPROP 2 LAST CDS_LIB pure_quanta
J 0
(-1625 2375);
DISPLAY INVISIBLE (-1625 2375);
FORCEPROP 1 LAST PART_NUMBER CS03302JB10
J 0
(-1600 2425);
DISPLAY 0.489362 (-1600 2425);
PAINT SKYBLUE (-1600 2425);
DISPLAY INVISIBLE (-1600 2425);
FORCEPROP 1 LAST PATH I224
J 0
(-1675 2525);
DISPLAY 0.978723 (-1675 2525);
PAINT WHITE (-1675 2525);
DISPLAY INVISIBLE (-1675 2525);
FORCEADD Q_RES..1
(-1625 2275);
FORCEPROP 1 LAST LOCATION R309
J 0
(-1875 2275);
DISPLAY 0.617021 (-1875 2275);
PAINT SKYBLUE (-1875 2275);
FORCEPROP 2 LAST SEC 1
J 0
(-1675 2475);
DISPLAY 0.680851 (-1675 2475);
PAINT MONO (-1675 2475);
DISPLAY INVISIBLE (-1675 2475);
FORCEPROP 1 LASTPIN (-1725 2275) $PN 1
J 0
(-1713 2287);
DISPLAY 0.787234 (-1713 2287);
PAINT MONO (-1713 2287);
FORCEPROP 1 LASTPIN (-1525 2275) $PN 2
J 0
(-1563 2287);
DISPLAY 0.787234 (-1563 2287);
PAINT MONO (-1563 2287);
FORCEPROP 1 LAST VALUE 33
J 2
(-1425 2275);
DISPLAY 0.617021 (-1425 2275);
PAINT SKYBLUE (-1425 2275);
FORCEPROP 1 LAST PACK_TYPE 0402LF
J 0
(-1575 2200);
DISPLAY 0.489362 (-1575 2200);
PAINT SKYBLUE (-1575 2200);
DISPLAY INVISIBLE (-1575 2200);
FORCEPROP 2 LAST SEC_TYPE 0402LF
J 0
(-1675 2475);
DISPLAY 0.680851 (-1675 2475);
DISPLAY INVISIBLE (-1675 2475);
FORCEPROP 1 LAST TOLERANCE 5%
J 0
(-1650 2200);
DISPLAY 0.489362 (-1650 2200);
PAINT SKYBLUE (-1650 2200);
DISPLAY INVISIBLE (-1650 2200);
FORCEPROP 1 LAST MATERIAL CHIP
J 0
(-1200 2200);
DISPLAY 0.489362 (-1200 2200);
PAINT SKYBLUE (-1200 2200);
DISPLAY INVISIBLE (-1200 2200);
FORCEPROP 1 LAST WATTAGE 1/16W
J 2
(-1225 2200);
DISPLAY 0.489362 (-1225 2200);
PAINT SKYBLUE (-1225 2200);
DISPLAY INVISIBLE (-1225 2200);
FORCEPROP 2 LAST CDS_LIB pure_quanta
J 0
(-1625 2275);
DISPLAY INVISIBLE (-1625 2275);
FORCEPROP 1 LAST PART_NUMBER CS03302JB10
J 0
(-1600 2325);
DISPLAY 0.489362 (-1600 2325);
PAINT SKYBLUE (-1600 2325);
DISPLAY INVISIBLE (-1600 2325);
FORCEPROP 1 LAST PATH I225
J 0
(-1675 2425);
DISPLAY 0.978723 (-1675 2425);
PAINT WHITE (-1675 2425);
DISPLAY INVISIBLE (-1675 2425);
FORCEADD Q_RES..1
(2875 850);
FORCEPROP 1 LAST LOCATION R6856
J 0
(2600 875);
DISPLAY 0.617021 (2600 875);
PAINT SKYBLUE (2600 875);
FORCEPROP 0 LAST $SEC 1
J 0
(2600 925);
DISPLAY 0.680851 (2600 925);
PAINT MONO (2600 925);
DISPLAY INVISIBLE (2600 925);
FORCEPROP 0 LAST CDS_SEC 1
J 0
(2600 925);
DISPLAY 0.680851 (2600 925);
DISPLAY INVISIBLE (2600 925);
FORCEPROP 1 LASTPIN (2775 850) $PN 1
J 0
(2787 862);
DISPLAY 0.787234 (2787 862);
PAINT MONO (2787 862);
FORCEPROP 1 LASTPIN (2975 850) $PN 2
J 0
(2937 862);
DISPLAY 0.787234 (2937 862);
PAINT MONO (2937 862);
FORCEPROP 1 LAST VALUE 33
J 2
(3075 850);
DISPLAY 0.617021 (3075 850);
PAINT SKYBLUE (3075 850);
FORCEPROP 2 LAST CDS_LIB pure_quanta
J 0
(2875 850);
DISPLAY INVISIBLE (2875 850);
FORCEPROP 1 LAST WATTAGE 1/16W
J 2
(3275 775);
DISPLAY 0.489362 (3275 775);
PAINT SKYBLUE (3275 775);
DISPLAY INVISIBLE (3275 775);
FORCEPROP 1 LAST MATERIAL CHIP
J 0
(3300 775);
DISPLAY 0.489362 (3300 775);
PAINT SKYBLUE (3300 775);
DISPLAY INVISIBLE (3300 775);
FORCEPROP 1 LAST TOLERANCE 5%
J 0
(2850 775);
DISPLAY 0.489362 (2850 775);
PAINT SKYBLUE (2850 775);
DISPLAY INVISIBLE (2850 775);
FORCEPROP 1 LAST PACK_TYPE 0402LF
J 0
(2925 775);
DISPLAY 0.489362 (2925 775);
PAINT SKYBLUE (2925 775);
DISPLAY INVISIBLE (2925 775);
FORCEPROP 1 LAST PART_NUMBER CS03302JB10
J 0
(2900 900);
DISPLAY 0.489362 (2900 900);
PAINT SKYBLUE (2900 900);
DISPLAY INVISIBLE (2900 900);
FORCEPROP 1 LAST PATH I226
J 0
(2825 1000);
DISPLAY 0.978723 (2825 1000);
PAINT WHITE (2825 1000);
DISPLAY INVISIBLE (2825 1000);
FORCEADD Q_RES..1
(2875 750);
FORCEPROP 1 LAST LOCATION R6857
J 0
(2600 775);
DISPLAY 0.617021 (2600 775);
PAINT SKYBLUE (2600 775);
FORCEPROP 0 LAST $SEC 1
J 0
(2600 825);
DISPLAY 0.680851 (2600 825);
PAINT MONO (2600 825);
DISPLAY INVISIBLE (2600 825);
FORCEPROP 0 LAST CDS_SEC 1
J 0
(2600 825);
DISPLAY 0.680851 (2600 825);
DISPLAY INVISIBLE (2600 825);
FORCEPROP 1 LASTPIN (2775 750) $PN 1
J 0
(2787 762);
DISPLAY 0.787234 (2787 762);
PAINT MONO (2787 762);
FORCEPROP 1 LASTPIN (2975 750) $PN 2
J 0
(2937 762);
DISPLAY 0.787234 (2937 762);
PAINT MONO (2937 762);
FORCEPROP 1 LAST VALUE 33
J 2
(3075 750);
DISPLAY 0.617021 (3075 750);
PAINT SKYBLUE (3075 750);
FORCEPROP 2 LAST CDS_LIB pure_quanta
J 0
(2875 750);
DISPLAY INVISIBLE (2875 750);
FORCEPROP 1 LAST WATTAGE 1/16W
J 2
(3275 675);
DISPLAY 0.489362 (3275 675);
PAINT SKYBLUE (3275 675);
DISPLAY INVISIBLE (3275 675);
FORCEPROP 1 LAST MATERIAL CHIP
J 0
(3300 675);
DISPLAY 0.489362 (3300 675);
PAINT SKYBLUE (3300 675);
DISPLAY INVISIBLE (3300 675);
FORCEPROP 1 LAST TOLERANCE 5%
J 0
(2850 675);
DISPLAY 0.489362 (2850 675);
PAINT SKYBLUE (2850 675);
DISPLAY INVISIBLE (2850 675);
FORCEPROP 1 LAST PACK_TYPE 0402LF
J 0
(2925 675);
DISPLAY 0.489362 (2925 675);
PAINT SKYBLUE (2925 675);
DISPLAY INVISIBLE (2925 675);
FORCEPROP 1 LAST PART_NUMBER CS03302JB10
J 0
(2900 800);
DISPLAY 0.489362 (2900 800);
PAINT SKYBLUE (2900 800);
DISPLAY INVISIBLE (2900 800);
FORCEPROP 1 LAST PATH I227
J 0
(2825 900);
DISPLAY 0.978723 (2825 900);
PAINT WHITE (2825 900);
DISPLAY INVISIBLE (2825 900);
FORCEADD Q_RES..1
R 2
(2550 5525);
FORCEPROP 1 LAST LOCATION R6782
J 2
(2400 5525);
DISPLAY 0.617021 (2400 5525);
PAINT SKYBLUE (2400 5525);
FORCEPROP 2 LAST SEC 1
J 2
(2600 5725);
DISPLAY 0.680851 (2600 5725);
PAINT MONO (2600 5725);
DISPLAY INVISIBLE (2600 5725);
FORCEPROP 1 LASTPIN (2650 5525) $PN 1
J 2
(2638 5537);
DISPLAY 0.787234 (2638 5537);
PAINT MONO (2638 5537);
FORCEPROP 1 LASTPIN (2450 5525) $PN 2
J 2
(2488 5537);
DISPLAY 0.787234 (2488 5537);
PAINT MONO (2488 5537);
FORCEPROP 1 LAST VALUE 33
J 0
(2800 5525);
DISPLAY 0.617021 (2800 5525);
PAINT SKYBLUE (2800 5525);
FORCEPROP 1 LAST MATERIAL CHIP
J 2
(2775 5525);
DISPLAY 0.489362 (2775 5525);
PAINT SKYBLUE (2775 5525);
FORCEPROP 1 LAST WATTAGE 1/16W
J 0
(2150 5450);
DISPLAY 0.489362 (2150 5450);
PAINT SKYBLUE (2150 5450);
DISPLAY INVISIBLE (2150 5450);
FORCEPROP 1 LAST TOLERANCE 5%
J 2
(2575 5450);
DISPLAY 0.489362 (2575 5450);
PAINT SKYBLUE (2575 5450);
DISPLAY INVISIBLE (2575 5450);
FORCEPROP 2 LAST CDS_LIB pure_quanta
J 2
(2550 5525);
DISPLAY INVISIBLE (2550 5525);
FORCEPROP 2 LAST SEC_TYPE 0402LF
J 2
(2600 5725);
DISPLAY 0.680851 (2600 5725);
DISPLAY INVISIBLE (2600 5725);
FORCEPROP 1 LAST PACK_TYPE 0402LF
J 2
(2500 5450);
DISPLAY 0.489362 (2500 5450);
PAINT SKYBLUE (2500 5450);
DISPLAY INVISIBLE (2500 5450);
FORCEPROP 1 LAST PART_NUMBER CS03302JB10
J 2
(2525 5575);
DISPLAY 0.489362 (2525 5575);
PAINT SKYBLUE (2525 5575);
DISPLAY INVISIBLE (2525 5575);
FORCEPROP 1 LAST PATH I228
J 2
(2600 5675);
DISPLAY 0.978723 (2600 5675);
PAINT WHITE (2600 5675);
DISPLAY INVISIBLE (2600 5675);
FORCEADD Q_RES..1
R 2
(2550 5475);
FORCEPROP 1 LAST LOCATION R6783
J 2
(2400 5475);
DISPLAY 0.617021 (2400 5475);
PAINT SKYBLUE (2400 5475);
FORCEPROP 0 LAST $SEC 1
J 0
(2800 5525);
DISPLAY 0.680851 (2800 5525);
PAINT MONO (2800 5525);
DISPLAY INVISIBLE (2800 5525);
FORCEPROP 0 LAST CDS_SEC 1
J 0
(2800 5525);
DISPLAY 0.680851 (2800 5525);
DISPLAY INVISIBLE (2800 5525);
FORCEPROP 1 LASTPIN (2650 5475) $PN 1
J 2
(2638 5487);
DISPLAY 0.787234 (2638 5487);
PAINT MONO (2638 5487);
FORCEPROP 1 LASTPIN (2450 5475) $PN 2
J 2
(2488 5487);
DISPLAY 0.787234 (2488 5487);
PAINT MONO (2488 5487);
FORCEPROP 1 LAST VALUE 33
J 0
(2800 5475);
DISPLAY 0.617021 (2800 5475);
PAINT SKYBLUE (2800 5475);
FORCEPROP 1 LAST MATERIAL CHIP
J 2
(2775 5475);
DISPLAY 0.489362 (2775 5475);
PAINT SKYBLUE (2775 5475);
FORCEPROP 2 LAST CDS_LIB pure_quanta
J 0
(2550 5475);
DISPLAY INVISIBLE (2550 5475);
FORCEPROP 1 LAST WATTAGE 1/16W
J 0
(2150 5400);
DISPLAY 0.489362 (2150 5400);
PAINT SKYBLUE (2150 5400);
DISPLAY INVISIBLE (2150 5400);
FORCEPROP 1 LAST TOLERANCE 5%
J 2
(2575 5400);
DISPLAY 0.489362 (2575 5400);
PAINT SKYBLUE (2575 5400);
DISPLAY INVISIBLE (2575 5400);
FORCEPROP 1 LAST PACK_TYPE 0402LF
J 2
(2500 5400);
DISPLAY 0.489362 (2500 5400);
PAINT SKYBLUE (2500 5400);
DISPLAY INVISIBLE (2500 5400);
FORCEPROP 1 LAST PART_NUMBER CS03302JB10
J 2
(2525 5525);
DISPLAY 0.489362 (2525 5525);
PAINT SKYBLUE (2525 5525);
DISPLAY INVISIBLE (2525 5525);
FORCEPROP 1 LAST PATH I229
J 2
(2600 5625);
DISPLAY 0.978723 (2600 5625);
PAINT WHITE (2600 5625);
DISPLAY INVISIBLE (2600 5625);
FORCEADD Q_RES..1
(-2100 5500);
FORCEPROP 1 LAST LOCATION R6022
J 0
(-2350 5500);
DISPLAY 0.489362 (-2350 5500);
PAINT SKYBLUE (-2350 5500);
FORCEPROP 0 LAST $SEC 1
J 0
(-2250 5550);
DISPLAY 0.680851 (-2250 5550);
PAINT MONO (-2250 5550);
DISPLAY INVISIBLE (-2250 5550);
FORCEPROP 0 LAST CDS_SEC 1
J 0
(-2250 5550);
DISPLAY 0.680851 (-2250 5550);
DISPLAY INVISIBLE (-2250 5550);
FORCEPROP 1 LASTPIN (-2200 5500) $PN 1
J 0
(-2188 5512);
DISPLAY 0.489362 (-2188 5512);
PAINT MONO (-2188 5512);
FORCEPROP 1 LASTPIN (-2000 5500) $PN 2
J 0
(-2038 5512);
DISPLAY 0.489362 (-2038 5512);
PAINT MONO (-2038 5512);
FORCEPROP 1 LAST VALUE 2K
J 0
(-1975 5500);
DISPLAY 0.489362 (-1975 5500);
PAINT SKYBLUE (-1975 5500);
FORCEPROP 1 LAST MATERIAL EMPTY
J 0
(-2000 5475);
DISPLAY 0.489362 (-2000 5475);
PAINT SKYBLUE (-2000 5475);
DISPLAY INVISIBLE (-2000 5475);
FORCEPROP 1 LAST PACK_TYPE 0402LF
J 0
(-1850 5350);
DISPLAY 0.510638 (-1850 5350);
PAINT SKYBLUE (-1850 5350);
DISPLAY INVISIBLE (-1850 5350);
FORCEPROP 1 LAST TOLERANCE 5%
J 0
(-1975 5500);
DISPLAY 0.510638 (-1975 5500);
PAINT SKYBLUE (-1975 5500);
DISPLAY INVISIBLE (-1975 5500);
FORCEPROP 1 LAST WATTAGE 1/16W
J 2
(-2125 5350);
DISPLAY 0.510638 (-2125 5350);
PAINT SKYBLUE (-2125 5350);
DISPLAY INVISIBLE (-2125 5350);
FORCEPROP 2 LAST CDS_LIB pure_quanta
J 0
(-2100 5500);
DISPLAY INVISIBLE (-2100 5500);
FORCEPROP 1 LAST PART_NUMBER TMP_QCS22002JB29
J 0
(-2150 5600);
DISPLAY 0.510638 (-2150 5600);
PAINT SKYBLUE (-2150 5600);
DISPLAY INVISIBLE (-2150 5600);
FORCEPROP 1 LAST PATH I23
J 0
(-2150 5650);
DISPLAY 0.978723 (-2150 5650);
PAINT WHITE (-2150 5650);
DISPLAY INVISIBLE (-2150 5650);
FORCEADD Q_RES..1
(-1475 6375);
FORCEPROP 1 LAST LOCATION R364
J 0
(-1725 6375);
DISPLAY 0.787234 (-1725 6375);
FORCEPROP 2 LAST SEC 1
J 0
(-1525 6575);
DISPLAY 0.680851 (-1525 6575);
PAINT MONO (-1525 6575);
DISPLAY INVISIBLE (-1525 6575);
FORCEPROP 1 LASTPIN (-1575 6375) $PN 1
J 0
(-1563 6387);
DISPLAY 0.787234 (-1563 6387);
PAINT MONO (-1563 6387);
FORCEPROP 1 LASTPIN (-1375 6375) $PN 2
J 0
(-1413 6387);
DISPLAY 0.787234 (-1413 6387);
PAINT MONO (-1413 6387);
FORCEPROP 1 LAST WATTAGE 1/16W
J 2
(-1125 6325);
DISPLAY 0.638298 (-1125 6325);
FORCEPROP 1 LAST MATERIAL CHIP
J 0
(-1425 6325);
DISPLAY 0.638298 (-1425 6325);
FORCEPROP 1 LAST PACK_TYPE 0402LF
J 0
(-1750 6325);
DISPLAY 0.638298 (-1750 6325);
FORCEPROP 1 LAST VALUE 0
J 2
(-1300 6375);
DISPLAY 0.638298 (-1300 6375);
FORCEPROP 1 LAST TOLERANCE 5%
J 0
(-1525 6325);
DISPLAY 0.638298 (-1525 6325);
FORCEPROP 2 LAST SEC_TYPE 0402LF
J 0
(-1525 6575);
DISPLAY 0.680851 (-1525 6575);
DISPLAY INVISIBLE (-1525 6575);
FORCEPROP 2 LAST CDS_LIB pure_quanta
J 0
(-1475 6375);
DISPLAY INVISIBLE (-1475 6375);
FORCEPROP 1 LAST PART_NUMBER CS00002JB13
J 0
(-1600 6450);
DISPLAY 0.638298 (-1600 6450);
DISPLAY INVISIBLE (-1600 6450);
FORCEPROP 1 LAST PATH I231
J 0
(-1525 6525);
DISPLAY 0.978723 (-1525 6525);
PAINT WHITE (-1525 6525);
DISPLAY INVISIBLE (-1525 6525);
FORCEADD Q_RES..1
(-2100 5600);
FORCEPROP 1 LAST LOCATION R6020
J 0
(-2350 5600);
DISPLAY 0.489362 (-2350 5600);
PAINT SKYBLUE (-2350 5600);
FORCEPROP 0 LAST $SEC 1
J 0
(-2250 5650);
DISPLAY 0.680851 (-2250 5650);
PAINT MONO (-2250 5650);
DISPLAY INVISIBLE (-2250 5650);
FORCEPROP 0 LAST CDS_SEC 1
J 0
(-2250 5650);
DISPLAY 0.680851 (-2250 5650);
DISPLAY INVISIBLE (-2250 5650);
FORCEPROP 1 LASTPIN (-2200 5600) $PN 1
J 0
(-2188 5612);
DISPLAY 0.489362 (-2188 5612);
PAINT MONO (-2188 5612);
FORCEPROP 1 LASTPIN (-2000 5600) $PN 2
J 0
(-2038 5612);
DISPLAY 0.489362 (-2038 5612);
PAINT MONO (-2038 5612);
FORCEPROP 1 LAST MATERIAL EMPTY
J 0
(-2150 5625);
DISPLAY 0.489362 (-2150 5625);
PAINT SKYBLUE (-2150 5625);
FORCEPROP 1 LAST VALUE 2K
J 0
(-1975 5600);
DISPLAY 0.489362 (-1975 5600);
PAINT SKYBLUE (-1975 5600);
FORCEPROP 1 LAST PACK_TYPE 0402LF
J 0
(-1850 5450);
DISPLAY 0.510638 (-1850 5450);
PAINT SKYBLUE (-1850 5450);
DISPLAY INVISIBLE (-1850 5450);
FORCEPROP 1 LAST TOLERANCE 5%
J 0
(-1975 5600);
DISPLAY 0.510638 (-1975 5600);
PAINT SKYBLUE (-1975 5600);
DISPLAY INVISIBLE (-1975 5600);
FORCEPROP 1 LAST WATTAGE 1/16W
J 2
(-2125 5450);
DISPLAY 0.510638 (-2125 5450);
PAINT SKYBLUE (-2125 5450);
DISPLAY INVISIBLE (-2125 5450);
FORCEPROP 2 LAST CDS_LIB pure_quanta
J 0
(-2100 5600);
DISPLAY INVISIBLE (-2100 5600);
FORCEPROP 1 LAST PART_NUMBER TMP_QCS22002JB29
J 0
(-2150 5700);
DISPLAY 0.510638 (-2150 5700);
PAINT SKYBLUE (-2150 5700);
DISPLAY INVISIBLE (-2150 5700);
FORCEPROP 1 LAST PATH I24
J 0
(-2150 5750);
DISPLAY 0.978723 (-2150 5750);
PAINT WHITE (-2150 5750);
DISPLAY INVISIBLE (-2150 5750);
FORCEADD Q_RES..1
(-2100 5650);
FORCEPROP 1 LAST LOCATION R6019
J 0
(-2350 5650);
DISPLAY 0.489362 (-2350 5650);
PAINT SKYBLUE (-2350 5650);
FORCEPROP 0 LAST $SEC 1
J 0
(-2250 5700);
DISPLAY 0.680851 (-2250 5700);
PAINT MONO (-2250 5700);
DISPLAY INVISIBLE (-2250 5700);
FORCEPROP 0 LAST CDS_SEC 1
J 0
(-2250 5700);
DISPLAY 0.680851 (-2250 5700);
DISPLAY INVISIBLE (-2250 5700);
FORCEPROP 1 LASTPIN (-2200 5650) $PN 1
J 0
(-2188 5662);
DISPLAY 0.489362 (-2188 5662);
PAINT MONO (-2188 5662);
FORCEPROP 1 LASTPIN (-2000 5650) $PN 2
J 0
(-2038 5662);
DISPLAY 0.489362 (-2038 5662);
PAINT MONO (-2038 5662);
FORCEPROP 1 LAST VALUE 2K
J 0
(-1975 5650);
DISPLAY 0.489362 (-1975 5650);
PAINT SKYBLUE (-1975 5650);
FORCEPROP 1 LAST MATERIAL EMPTY
J 0
(-2150 5675);
DISPLAY 0.489362 (-2150 5675);
PAINT SKYBLUE (-2150 5675);
FORCEPROP 1 LAST PACK_TYPE 0402LF
J 0
(-1850 5500);
DISPLAY 0.510638 (-1850 5500);
PAINT SKYBLUE (-1850 5500);
DISPLAY INVISIBLE (-1850 5500);
FORCEPROP 1 LAST TOLERANCE 5%
J 0
(-1975 5650);
DISPLAY 0.510638 (-1975 5650);
PAINT SKYBLUE (-1975 5650);
DISPLAY INVISIBLE (-1975 5650);
FORCEPROP 1 LAST WATTAGE 1/16W
J 2
(-2125 5500);
DISPLAY 0.510638 (-2125 5500);
PAINT SKYBLUE (-2125 5500);
DISPLAY INVISIBLE (-2125 5500);
FORCEPROP 2 LAST CDS_LIB pure_quanta
J 0
(-2100 5650);
DISPLAY INVISIBLE (-2100 5650);
FORCEPROP 1 LAST PART_NUMBER TMP_QCS22002JB29
J 0
(-2150 5750);
DISPLAY 0.510638 (-2150 5750);
PAINT SKYBLUE (-2150 5750);
DISPLAY INVISIBLE (-2150 5750);
FORCEPROP 1 LAST PATH I25
J 0
(-2150 5800);
DISPLAY 0.978723 (-2150 5800);
PAINT WHITE (-2150 5800);
DISPLAY INVISIBLE (-2150 5800);
FORCEADD UNIVERSAL_POWER..1
(-2525 6075);
FORCEPROP 3 LASTPIN (-2525 6025) SIG_NAME P3V3_AUX\g
J 0
(-2515 6035);
DISPLAY 0.659574 (-2515 6035);
PAINT MONO (-2515 6035);
DISPLAY INVISIBLE (-2515 6035);
FORCEPROP 1 LAST HDL_POWER P3V3_AUX
J 1
(-2525 6125);
DISPLAY 0.489362 (-2525 6125);
PAINT GREEN (-2525 6125);
FORCEPROP 2 LAST CDS_LIB pure_quanta_power
J 0
(-2525 6075);
DISPLAY INVISIBLE (-2525 6075);
FORCEPROP 1 LAST PATH I26
J 0
(-2475 6100);
DISPLAY 0.872340 (-2475 6100);
PAINT AQUA (-2475 6100);
DISPLAY INVISIBLE (-2475 6100);
FORCEADD Q_RES..1
(-2100 5700);
FORCEPROP 1 LAST LOCATION R6018
J 0
(-2350 5700);
DISPLAY 0.489362 (-2350 5700);
PAINT SKYBLUE (-2350 5700);
FORCEPROP 0 LAST $SEC 1
J 0
(-2250 5750);
DISPLAY 0.680851 (-2250 5750);
PAINT MONO (-2250 5750);
DISPLAY INVISIBLE (-2250 5750);
FORCEPROP 0 LAST CDS_SEC 1
J 0
(-2250 5750);
DISPLAY 0.680851 (-2250 5750);
DISPLAY INVISIBLE (-2250 5750);
FORCEPROP 1 LASTPIN (-2200 5700) $PN 1
J 0
(-2188 5712);
DISPLAY 0.489362 (-2188 5712);
PAINT MONO (-2188 5712);
FORCEPROP 1 LASTPIN (-2000 5700) $PN 2
J 0
(-2038 5712);
DISPLAY 0.489362 (-2038 5712);
PAINT MONO (-2038 5712);
FORCEPROP 1 LAST VALUE 2K
J 0
(-1975 5700);
DISPLAY 0.489362 (-1975 5700);
PAINT SKYBLUE (-1975 5700);
FORCEPROP 1 LAST MATERIAL EMPTY
J 0
(-2150 5725);
DISPLAY 0.489362 (-2150 5725);
PAINT SKYBLUE (-2150 5725);
FORCEPROP 1 LAST PACK_TYPE 0402LF
J 0
(-1850 5550);
DISPLAY 0.510638 (-1850 5550);
PAINT SKYBLUE (-1850 5550);
DISPLAY INVISIBLE (-1850 5550);
FORCEPROP 1 LAST TOLERANCE 5%
J 0
(-1975 5700);
DISPLAY 0.510638 (-1975 5700);
PAINT SKYBLUE (-1975 5700);
DISPLAY INVISIBLE (-1975 5700);
FORCEPROP 1 LAST WATTAGE 1/16W
J 2
(-2125 5550);
DISPLAY 0.510638 (-2125 5550);
PAINT SKYBLUE (-2125 5550);
DISPLAY INVISIBLE (-2125 5550);
FORCEPROP 2 LAST CDS_LIB pure_quanta
J 0
(-2100 5700);
DISPLAY INVISIBLE (-2100 5700);
FORCEPROP 1 LAST PART_NUMBER TMP_QCS22002JB29
J 0
(-2150 5800);
DISPLAY 0.510638 (-2150 5800);
PAINT SKYBLUE (-2150 5800);
DISPLAY INVISIBLE (-2150 5800);
FORCEPROP 1 LAST PATH I27
J 0
(-2150 5850);
DISPLAY 0.978723 (-2150 5850);
PAINT WHITE (-2150 5850);
DISPLAY INVISIBLE (-2150 5850);
FORCEADD Q_RES..1
(-2100 5750);
FORCEPROP 1 LAST LOCATION R6017
J 0
(-2350 5750);
DISPLAY 0.489362 (-2350 5750);
PAINT SKYBLUE (-2350 5750);
FORCEPROP 0 LAST $SEC 1
J 0
(-2250 5800);
DISPLAY 0.680851 (-2250 5800);
PAINT MONO (-2250 5800);
DISPLAY INVISIBLE (-2250 5800);
FORCEPROP 0 LAST CDS_SEC 1
J 0
(-2250 5800);
DISPLAY 0.680851 (-2250 5800);
DISPLAY INVISIBLE (-2250 5800);
FORCEPROP 1 LASTPIN (-2200 5750) $PN 1
J 0
(-2188 5762);
DISPLAY 0.489362 (-2188 5762);
PAINT MONO (-2188 5762);
FORCEPROP 1 LASTPIN (-2000 5750) $PN 2
J 0
(-2038 5762);
DISPLAY 0.489362 (-2038 5762);
PAINT MONO (-2038 5762);
FORCEPROP 1 LAST MATERIAL EMPTY
J 0
(-2150 5775);
DISPLAY 0.489362 (-2150 5775);
PAINT SKYBLUE (-2150 5775);
FORCEPROP 1 LAST VALUE 2K
J 0
(-1975 5750);
DISPLAY 0.489362 (-1975 5750);
PAINT SKYBLUE (-1975 5750);
FORCEPROP 2 LAST CDS_LIB pure_quanta
J 0
(-2100 5750);
DISPLAY INVISIBLE (-2100 5750);
FORCEPROP 1 LAST WATTAGE 1/16W
J 2
(-2125 5600);
DISPLAY 0.510638 (-2125 5600);
PAINT SKYBLUE (-2125 5600);
DISPLAY INVISIBLE (-2125 5600);
FORCEPROP 1 LAST TOLERANCE 5%
J 0
(-1975 5750);
DISPLAY 0.510638 (-1975 5750);
PAINT SKYBLUE (-1975 5750);
DISPLAY INVISIBLE (-1975 5750);
FORCEPROP 1 LAST PACK_TYPE 0402LF
J 0
(-1850 5600);
DISPLAY 0.510638 (-1850 5600);
PAINT SKYBLUE (-1850 5600);
DISPLAY INVISIBLE (-1850 5600);
FORCEPROP 1 LAST PART_NUMBER TMP_QCS22002JB29
J 0
(-2150 5850);
DISPLAY 0.510638 (-2150 5850);
PAINT SKYBLUE (-2150 5850);
DISPLAY INVISIBLE (-2150 5850);
FORCEPROP 1 LAST PATH I28
J 0
(-2150 5900);
DISPLAY 0.978723 (-2150 5900);
PAINT WHITE (-2150 5900);
DISPLAY INVISIBLE (-2150 5900);
FORCEADD Q_RES..1
(-2100 5800);
FORCEPROP 1 LAST LOCATION R6016
J 0
(-2350 5800);
DISPLAY 0.489362 (-2350 5800);
PAINT SKYBLUE (-2350 5800);
FORCEPROP 0 LAST $SEC 1
J 0
(-2250 5850);
DISPLAY 0.680851 (-2250 5850);
PAINT MONO (-2250 5850);
DISPLAY INVISIBLE (-2250 5850);
FORCEPROP 0 LAST CDS_SEC 1
J 0
(-2250 5850);
DISPLAY 0.680851 (-2250 5850);
DISPLAY INVISIBLE (-2250 5850);
FORCEPROP 1 LASTPIN (-2200 5800) $PN 1
J 0
(-2188 5812);
DISPLAY 0.489362 (-2188 5812);
PAINT MONO (-2188 5812);
FORCEPROP 1 LASTPIN (-2000 5800) $PN 2
J 0
(-2038 5812);
DISPLAY 0.489362 (-2038 5812);
PAINT MONO (-2038 5812);
FORCEPROP 1 LAST VALUE 2K
J 0
(-1975 5800);
DISPLAY 0.489362 (-1975 5800);
PAINT SKYBLUE (-1975 5800);
FORCEPROP 1 LAST MATERIAL EMPTY
J 0
(-2150 5825);
DISPLAY 0.489362 (-2150 5825);
PAINT SKYBLUE (-2150 5825);
FORCEPROP 1 LAST PACK_TYPE 0402LF
J 0
(-1850 5650);
DISPLAY 0.510638 (-1850 5650);
PAINT SKYBLUE (-1850 5650);
DISPLAY INVISIBLE (-1850 5650);
FORCEPROP 1 LAST TOLERANCE 5%
J 0
(-1975 5800);
DISPLAY 0.510638 (-1975 5800);
PAINT SKYBLUE (-1975 5800);
DISPLAY INVISIBLE (-1975 5800);
FORCEPROP 1 LAST WATTAGE 1/16W
J 2
(-2125 5650);
DISPLAY 0.510638 (-2125 5650);
PAINT SKYBLUE (-2125 5650);
DISPLAY INVISIBLE (-2125 5650);
FORCEPROP 2 LAST CDS_LIB pure_quanta
J 0
(-2100 5800);
DISPLAY INVISIBLE (-2100 5800);
FORCEPROP 1 LAST PART_NUMBER TMP_QCS22002JB29
J 0
(-2150 5900);
DISPLAY 0.510638 (-2150 5900);
PAINT SKYBLUE (-2150 5900);
DISPLAY INVISIBLE (-2150 5900);
FORCEPROP 1 LAST PATH I29
J 0
(-2150 5950);
DISPLAY 0.978723 (-2150 5950);
PAINT WHITE (-2150 5950);
DISPLAY INVISIBLE (-2150 5950);
FORCEADD OFFPAGE..3
R 2
(-2700 2275);
FORCEPROP 2 LAST $XR0 253 
J 0
(-2980 2275);
DISPLAY 0.638298 (-2980 2275);
PAINT MONO (-2980 2275);
FORCEPROP 2 LAST CDS_LIB standard
J 0
(-2700 2275);
DISPLAY INVISIBLE (-2700 2275);
FORCEPROP 1 LAST OFFPAGE TRUE
J 2
(-3025 2150);
DISPLAY 0.872340 (-3025 2150);
PAINT GREEN (-3025 2150);
DISPLAY INVISIBLE (-3025 2150);
FORCEPROP 1 LAST COMMENT_BODY TRUE
J 2
(-2650 2175);
DISPLAY 0.872340 (-2650 2175);
PAINT GREEN (-2650 2175);
DISPLAY INVISIBLE (-2650 2175);
FORCEPROP 2 LAST PATH I3
J 0
(-2650 2350);
DISPLAY 0.680851 (-2650 2350);
DISPLAY INVISIBLE (-2650 2350);
FORCEADD Q_RES..1
(-2100 6000);
FORCEPROP 1 LAST LOCATION R1546
J 0
(-2350 6000);
DISPLAY 0.489362 (-2350 6000);
PAINT SKYBLUE (-2350 6000);
FORCEPROP 0 LAST $SEC 1
J 0
(-1975 6025);
DISPLAY 0.680851 (-1975 6025);
PAINT MONO (-1975 6025);
DISPLAY INVISIBLE (-1975 6025);
FORCEPROP 0 LAST CDS_SEC 1
J 0
(-1975 6025);
DISPLAY 0.680851 (-1975 6025);
DISPLAY INVISIBLE (-1975 6025);
FORCEPROP 1 LASTPIN (-2200 6000) $PN 1
J 0
(-2188 6012);
DISPLAY 0.787234 (-2188 6012);
PAINT MONO (-2188 6012);
FORCEPROP 1 LASTPIN (-2000 6000) $PN 2
J 0
(-2038 6012);
DISPLAY 0.787234 (-2038 6012);
PAINT MONO (-2038 6012);
FORCEPROP 1 LAST VALUE 1K
J 0
(-1975 6000);
DISPLAY 0.489362 (-1975 6000);
PAINT SKYBLUE (-1975 6000);
FORCEPROP 1 LAST WATTAGE 1/16W
J 2
(-2125 5850);
DISPLAY 0.510638 (-2125 5850);
PAINT SKYBLUE (-2125 5850);
DISPLAY INVISIBLE (-2125 5850);
FORCEPROP 1 LAST MATERIAL CHIP
J 0
(-2000 5975);
DISPLAY 0.489362 (-2000 5975);
PAINT SKYBLUE (-2000 5975);
DISPLAY INVISIBLE (-2000 5975);
FORCEPROP 1 LAST PACK_TYPE 0402LF
J 0
(-1850 5850);
DISPLAY 0.510638 (-1850 5850);
PAINT SKYBLUE (-1850 5850);
DISPLAY INVISIBLE (-1850 5850);
FORCEPROP 2 LAST CDS_LIB pure_quanta
J 0
(-2100 6000);
DISPLAY INVISIBLE (-2100 6000);
FORCEPROP 1 LAST TOLERANCE 1%
J 0
(-1975 6000);
DISPLAY 0.510638 (-1975 6000);
PAINT SKYBLUE (-1975 6000);
DISPLAY INVISIBLE (-1975 6000);
FORCEPROP 1 LAST PART_NUMBER CS21002FB06
J 0
(-2150 6100);
DISPLAY 0.510638 (-2150 6100);
PAINT SKYBLUE (-2150 6100);
DISPLAY INVISIBLE (-2150 6100);
FORCEPROP 1 LAST PATH I30
J 0
(-2150 6150);
DISPLAY 0.978723 (-2150 6150);
PAINT WHITE (-2150 6150);
DISPLAY INVISIBLE (-2150 6150);
FORCEADD UNIVERSAL_POWER..1
(-2050 6650);
FORCEPROP 3 LASTPIN (-2050 6600) SIG_NAME P3V_BAT_R\g
J 0
(-2040 6610);
DISPLAY 0.659574 (-2040 6610);
PAINT MONO (-2040 6610);
DISPLAY INVISIBLE (-2040 6610);
FORCEPROP 1 LAST HDL_POWER P3V_BAT_R
J 1
(-2050 6700);
DISPLAY 0.489362 (-2050 6700);
PAINT GREEN (-2050 6700);
FORCEPROP 2 LAST CDS_LIB pure_quanta_power
J 0
(-2050 6650);
DISPLAY INVISIBLE (-2050 6650);
FORCEPROP 1 LAST PATH I31
J 0
(-2000 6675);
DISPLAY 0.872340 (-2000 6675);
PAINT AQUA (-2000 6675);
DISPLAY INVISIBLE (-2000 6675);
FORCEADD Q_RES..1
(-1600 4850);
FORCEPROP 1 LAST LOCATION R6027
J 0
(-1725 4850);
DISPLAY 0.489362 (-1725 4850);
PAINT SKYBLUE (-1725 4850);
FORCEPROP 0 LAST $SEC 1
J 0
(-1725 4900);
DISPLAY 0.680851 (-1725 4900);
PAINT MONO (-1725 4900);
DISPLAY INVISIBLE (-1725 4900);
FORCEPROP 0 LAST CDS_SEC 1
J 0
(-1725 4900);
DISPLAY 0.680851 (-1725 4900);
DISPLAY INVISIBLE (-1725 4900);
FORCEPROP 1 LASTPIN (-1700 4850) $PN 1
J 0
(-1688 4862);
DISPLAY 0.489362 (-1688 4862);
PAINT MONO (-1688 4862);
FORCEPROP 1 LASTPIN (-1500 4850) $PN 2
J 0
(-1538 4862);
DISPLAY 0.489362 (-1538 4862);
PAINT MONO (-1538 4862);
FORCEPROP 1 LAST VALUE 4.7K
J 0
(-1475 4850);
DISPLAY 0.489362 (-1475 4850);
PAINT SKYBLUE (-1475 4850);
FORCEPROP 1 LAST MATERIAL EMPTY
J 0
(-1500 4825);
DISPLAY 0.489362 (-1500 4825);
PAINT SKYBLUE (-1500 4825);
FORCEPROP 1 LAST WATTAGE 1/16W
J 2
(-1625 4700);
DISPLAY 0.510638 (-1625 4700);
PAINT SKYBLUE (-1625 4700);
DISPLAY INVISIBLE (-1625 4700);
FORCEPROP 1 LAST TOLERANCE 5%
J 0
(-1475 4850);
DISPLAY 0.510638 (-1475 4850);
PAINT SKYBLUE (-1475 4850);
DISPLAY INVISIBLE (-1475 4850);
FORCEPROP 1 LAST PACK_TYPE 0402LF
J 0
(-1350 4700);
DISPLAY 0.510638 (-1350 4700);
PAINT SKYBLUE (-1350 4700);
DISPLAY INVISIBLE (-1350 4700);
FORCEPROP 2 LAST CDS_LIB pure_quanta
J 0
(-1600 4850);
DISPLAY INVISIBLE (-1600 4850);
FORCEPROP 1 LAST PART_NUMBER CS24702JB10
J 0
(-1650 4950);
DISPLAY 0.510638 (-1650 4950);
PAINT SKYBLUE (-1650 4950);
DISPLAY INVISIBLE (-1650 4950);
FORCEPROP 1 LAST PATH I32
J 0
(-1650 5000);
DISPLAY 0.978723 (-1650 5000);
PAINT WHITE (-1650 5000);
DISPLAY INVISIBLE (-1650 5000);
FORCEADD OFFPAGE..2
(-1025 5400);
FORCEPROP 2 LAST $XR1 150 
J 0
(-746 5400);
DISPLAY 0.638298 (-746 5400);
PAINT MONO (-746 5400);
FORCEPROP 2 LAST $XR0 80 
J 0
(-836 5400);
DISPLAY 0.638298 (-836 5400);
PAINT MONO (-836 5400);
FORCEPROP 2 LAST CDS_LIB standard
J 0
(-1025 5400);
DISPLAY INVISIBLE (-1025 5400);
FORCEPROP 1 LAST OFFPAGE TRUE
J 0
(-700 5275);
DISPLAY 0.872340 (-700 5275);
PAINT GREEN (-700 5275);
DISPLAY INVISIBLE (-700 5275);
FORCEPROP 1 LAST COMMENT_BODY TRUE
J 0
(-1070 5305);
DISPLAY 0.872340 (-1070 5305);
PAINT PEACH (-1070 5305);
DISPLAY INVISIBLE (-1070 5305);
FORCEPROP 2 LAST PATH I33
J 0
(-850 5475);
DISPLAY 0.680851 (-850 5475);
DISPLAY INVISIBLE (-850 5475);
FORCEADD OFFPAGE..2
(-1025 5450);
FORCEPROP 2 LAST $XR1 80 
J 0
(-716 5450);
DISPLAY 0.638298 (-716 5450);
PAINT MONO (-716 5450);
FORCEPROP 2 LAST $XR0 150 
J 0
(-836 5450);
DISPLAY 0.638298 (-836 5450);
PAINT MONO (-836 5450);
FORCEPROP 2 LAST CDS_LIB standard
J 0
(-1025 5450);
DISPLAY INVISIBLE (-1025 5450);
FORCEPROP 1 LAST OFFPAGE TRUE
J 0
(-700 5325);
DISPLAY 0.872340 (-700 5325);
PAINT GREEN (-700 5325);
DISPLAY INVISIBLE (-700 5325);
FORCEPROP 1 LAST COMMENT_BODY TRUE
J 0
(-1070 5355);
DISPLAY 0.872340 (-1070 5355);
PAINT PEACH (-1070 5355);
DISPLAY INVISIBLE (-1070 5355);
FORCEPROP 2 LAST PATH I34
J 0
(-850 5525);
DISPLAY 0.680851 (-850 5525);
DISPLAY INVISIBLE (-850 5525);
FORCEADD OFFPAGE..2
(-1025 5500);
FORCEPROP 2 LAST $XR1 150 
J 0
(-746 5500);
DISPLAY 0.638298 (-746 5500);
PAINT MONO (-746 5500);
FORCEPROP 2 LAST $XR0 80 
J 0
(-836 5500);
DISPLAY 0.638298 (-836 5500);
PAINT MONO (-836 5500);
FORCEPROP 2 LAST CDS_LIB standard
J 0
(-1025 5500);
DISPLAY INVISIBLE (-1025 5500);
FORCEPROP 1 LAST OFFPAGE TRUE
J 0
(-700 5375);
DISPLAY 0.872340 (-700 5375);
PAINT GREEN (-700 5375);
DISPLAY INVISIBLE (-700 5375);
FORCEPROP 1 LAST COMMENT_BODY TRUE
J 0
(-1070 5405);
DISPLAY 0.872340 (-1070 5405);
PAINT PEACH (-1070 5405);
DISPLAY INVISIBLE (-1070 5405);
FORCEPROP 2 LAST PATH I35
J 0
(-850 5575);
DISPLAY 0.680851 (-850 5575);
DISPLAY INVISIBLE (-850 5575);
FORCEADD OFFPAGE..2
(-1025 5550);
FORCEPROP 2 LAST $XR1 80 
J 0
(-716 5550);
DISPLAY 0.638298 (-716 5550);
PAINT MONO (-716 5550);
FORCEPROP 2 LAST $XR0 150 
J 0
(-836 5550);
DISPLAY 0.638298 (-836 5550);
PAINT MONO (-836 5550);
FORCEPROP 2 LAST CDS_LIB standard
J 0
(-1025 5550);
DISPLAY INVISIBLE (-1025 5550);
FORCEPROP 1 LAST OFFPAGE TRUE
J 0
(-700 5425);
DISPLAY 0.872340 (-700 5425);
PAINT GREEN (-700 5425);
DISPLAY INVISIBLE (-700 5425);
FORCEPROP 1 LAST COMMENT_BODY TRUE
J 0
(-1070 5455);
DISPLAY 0.872340 (-1070 5455);
PAINT PEACH (-1070 5455);
DISPLAY INVISIBLE (-1070 5455);
FORCEPROP 2 LAST PATH I36
J 0
(-850 5625);
DISPLAY 0.680851 (-850 5625);
DISPLAY INVISIBLE (-850 5625);
FORCEADD OFFPAGE..2
(-1025 5600);
FORCEPROP 2 LAST $XR1 80 
J 0
(-716 5600);
DISPLAY 0.638298 (-716 5600);
PAINT MONO (-716 5600);
FORCEPROP 2 LAST $XR0 150 
J 0
(-836 5600);
DISPLAY 0.638298 (-836 5600);
PAINT MONO (-836 5600);
FORCEPROP 2 LAST CDS_LIB standard
J 0
(-1025 5600);
DISPLAY INVISIBLE (-1025 5600);
FORCEPROP 1 LAST OFFPAGE TRUE
J 0
(-700 5475);
DISPLAY 0.872340 (-700 5475);
PAINT GREEN (-700 5475);
DISPLAY INVISIBLE (-700 5475);
FORCEPROP 1 LAST COMMENT_BODY TRUE
J 0
(-1070 5505);
DISPLAY 0.872340 (-1070 5505);
PAINT PEACH (-1070 5505);
DISPLAY INVISIBLE (-1070 5505);
FORCEPROP 2 LAST PATH I37
J 0
(-850 5675);
DISPLAY 0.680851 (-850 5675);
DISPLAY INVISIBLE (-850 5675);
FORCEADD OFFPAGE..2
(-1025 5650);
FORCEPROP 2 LAST $XR1 80 
J 0
(-716 5650);
DISPLAY 0.638298 (-716 5650);
PAINT MONO (-716 5650);
FORCEPROP 2 LAST $XR0 150 
J 0
(-836 5650);
DISPLAY 0.638298 (-836 5650);
PAINT MONO (-836 5650);
FORCEPROP 2 LAST CDS_LIB standard
J 0
(-1025 5650);
DISPLAY INVISIBLE (-1025 5650);
FORCEPROP 1 LAST OFFPAGE TRUE
J 0
(-700 5525);
DISPLAY 0.872340 (-700 5525);
PAINT GREEN (-700 5525);
DISPLAY INVISIBLE (-700 5525);
FORCEPROP 1 LAST COMMENT_BODY TRUE
J 0
(-1070 5555);
DISPLAY 0.872340 (-1070 5555);
PAINT PEACH (-1070 5555);
DISPLAY INVISIBLE (-1070 5555);
FORCEPROP 2 LAST PATH I38
J 0
(-850 5725);
DISPLAY 0.680851 (-850 5725);
DISPLAY INVISIBLE (-850 5725);
FORCEADD OFFPAGE..2
(-1025 5700);
FORCEPROP 2 LAST $XR1 150 
J 0
(-746 5700);
DISPLAY 0.638298 (-746 5700);
PAINT MONO (-746 5700);
FORCEPROP 2 LAST $XR0 80 
J 0
(-836 5700);
DISPLAY 0.638298 (-836 5700);
PAINT MONO (-836 5700);
FORCEPROP 2 LAST CDS_LIB standard
J 0
(-1025 5700);
DISPLAY INVISIBLE (-1025 5700);
FORCEPROP 1 LAST OFFPAGE TRUE
J 0
(-700 5575);
DISPLAY 0.872340 (-700 5575);
PAINT GREEN (-700 5575);
DISPLAY INVISIBLE (-700 5575);
FORCEPROP 1 LAST COMMENT_BODY TRUE
J 0
(-1070 5605);
DISPLAY 0.872340 (-1070 5605);
PAINT PEACH (-1070 5605);
DISPLAY INVISIBLE (-1070 5605);
FORCEPROP 2 LAST PATH I39
J 0
(-850 5775);
DISPLAY 0.680851 (-850 5775);
DISPLAY INVISIBLE (-850 5775);
FORCEADD OFFPAGE..4
R 2
(-2700 2375);
FORCEPROP 2 LAST $XR0 253 
J 0
(-2952 2375);
DISPLAY 0.638298 (-2952 2375);
PAINT MONO (-2952 2375);
FORCEPROP 2 LAST CDS_LIB standard
J 0
(-2700 2375);
DISPLAY INVISIBLE (-2700 2375);
FORCEPROP 1 LAST OFFPAGE TRUE
J 2
(-3025 2250);
DISPLAY 0.872340 (-3025 2250);
PAINT GREEN (-3025 2250);
DISPLAY INVISIBLE (-3025 2250);
FORCEPROP 1 LAST COMMENT_BODY TRUE
J 2
(-2675 2275);
DISPLAY 0.872340 (-2675 2275);
PAINT GREEN (-2675 2275);
DISPLAY INVISIBLE (-2675 2275);
FORCEPROP 2 LAST PATH I4
J 0
(-2650 2450);
DISPLAY 0.680851 (-2650 2450);
DISPLAY INVISIBLE (-2650 2450);
FORCEADD OFFPAGE..2
(-1025 5750);
FORCEPROP 2 LAST $XR1 80 
J 0
(-716 5750);
DISPLAY 0.638298 (-716 5750);
PAINT MONO (-716 5750);
FORCEPROP 2 LAST $XR0 150 
J 0
(-836 5750);
DISPLAY 0.638298 (-836 5750);
PAINT MONO (-836 5750);
FORCEPROP 2 LAST CDS_LIB standard
J 0
(-1025 5750);
DISPLAY INVISIBLE (-1025 5750);
FORCEPROP 1 LAST OFFPAGE TRUE
J 0
(-700 5625);
DISPLAY 0.872340 (-700 5625);
PAINT GREEN (-700 5625);
DISPLAY INVISIBLE (-700 5625);
FORCEPROP 1 LAST COMMENT_BODY TRUE
J 0
(-1070 5655);
DISPLAY 0.872340 (-1070 5655);
PAINT PEACH (-1070 5655);
DISPLAY INVISIBLE (-1070 5655);
FORCEPROP 2 LAST PATH I40
J 0
(-850 5825);
DISPLAY 0.680851 (-850 5825);
DISPLAY INVISIBLE (-850 5825);
FORCEADD OFFPAGE..2
(-1025 5800);
FORCEPROP 2 LAST $XR1 80 
J 0
(-716 5800);
DISPLAY 0.638298 (-716 5800);
PAINT MONO (-716 5800);
FORCEPROP 2 LAST $XR0 150 
J 0
(-836 5800);
DISPLAY 0.638298 (-836 5800);
PAINT MONO (-836 5800);
FORCEPROP 2 LAST CDS_LIB standard
J 0
(-1025 5800);
DISPLAY INVISIBLE (-1025 5800);
FORCEPROP 1 LAST OFFPAGE TRUE
J 0
(-700 5675);
DISPLAY 0.872340 (-700 5675);
PAINT GREEN (-700 5675);
DISPLAY INVISIBLE (-700 5675);
FORCEPROP 1 LAST COMMENT_BODY TRUE
J 0
(-1070 5705);
DISPLAY 0.872340 (-1070 5705);
PAINT PEACH (-1070 5705);
DISPLAY INVISIBLE (-1070 5705);
FORCEPROP 2 LAST PATH I41
J 0
(-850 5875);
DISPLAY 0.680851 (-850 5875);
DISPLAY INVISIBLE (-850 5875);
FORCEADD OFFPAGE..2
(-1025 6000);
FORCEPROP 2 LAST $XR1 80 
J 0
(-716 6000);
DISPLAY 0.638298 (-716 6000);
PAINT MONO (-716 6000);
FORCEPROP 2 LAST $XR0 150 
J 0
(-836 6000);
DISPLAY 0.638298 (-836 6000);
PAINT MONO (-836 6000);
FORCEPROP 2 LAST CDS_LIB standard
J 0
(-1025 6000);
DISPLAY INVISIBLE (-1025 6000);
FORCEPROP 1 LAST OFFPAGE TRUE
J 0
(-700 5875);
DISPLAY 0.872340 (-700 5875);
PAINT GREEN (-700 5875);
DISPLAY INVISIBLE (-700 5875);
FORCEPROP 1 LAST COMMENT_BODY TRUE
J 0
(-1070 5905);
DISPLAY 0.872340 (-1070 5905);
PAINT PEACH (-1070 5905);
DISPLAY INVISIBLE (-1070 5905);
FORCEPROP 2 LAST PATH I42
J 0
(-700 6050);
DISPLAY 0.680851 (-700 6050);
DISPLAY INVISIBLE (-700 6050);
FORCEADD UNIVERSAL_POWER..1
(-675 4850);
FORCEPROP 3 LASTPIN (-675 4800) SIG_NAME PVDD18_S5_P0\g
J 0
(-665 4810);
DISPLAY 0.659574 (-665 4810);
PAINT MONO (-665 4810);
DISPLAY INVISIBLE (-665 4810);
FORCEPROP 1 LAST HDL_POWER PVDD18_S5_P0
J 1
(-675 4900);
DISPLAY 0.489362 (-675 4900);
PAINT GREEN (-675 4900);
FORCEPROP 2 LAST CDS_LIB pure_quanta_power
J 0
(-675 4850);
DISPLAY INVISIBLE (-675 4850);
FORCEPROP 1 LAST PATH I43
J 0
(-625 4875);
DISPLAY 0.872340 (-625 4875);
PAINT AQUA (-625 4875);
DISPLAY INVISIBLE (-625 4875);
FORCEADD UNIVERSAL_GND..1
(-1225 4675);
FORCEPROP 3 LASTPIN (-1225 4725) SIG_NAME GND\g
J 0
(-1215 4735);
DISPLAY 0.659574 (-1215 4735);
PAINT MONO (-1215 4735);
DISPLAY INVISIBLE (-1215 4735);
FORCEPROP 2 LAST CDS_LIB pure_quanta_power
J 0
(-1225 4675);
DISPLAY INVISIBLE (-1225 4675);
FORCEPROP 1 LAST HDL_POWER GND
J 1
(-1200 4600);
DISPLAY 0.872340 (-1200 4600);
PAINT GREEN (-1200 4600);
DISPLAY INVISIBLE (-1200 4600);
FORCEPROP 1 LAST PATH I44
J 0
(-1150 4675);
DISPLAY 0.872340 (-1150 4675);
PAINT AQUA (-1150 4675);
DISPLAY INVISIBLE (-1150 4675);
FORCEADD VCC_CORE..1
(-975 6675);
FORCEPROP 3 LASTPIN (-975 6625) SIG_NAME SCM_VDD_RTC\g
J 0
(-965 6635);
DISPLAY 0.659574 (-965 6635);
PAINT MONO (-965 6635);
DISPLAY INVISIBLE (-965 6635);
FORCEPROP 1 LAST HDL_POWER SCM_VDD_RTC
J 1
(-975 6725);
DISPLAY 0.489362 (-975 6725);
PAINT GREEN (-975 6725);
FORCEPROP 2 LAST CDS_LIB pure_quanta_power
J 0
(-975 6675);
DISPLAY INVISIBLE (-975 6675);
FORCEPROP 1 LAST PATH I46
J 0
(-925 6700);
DISPLAY 0.872340 (-925 6700);
PAINT AQUA (-925 6700);
DISPLAY INVISIBLE (-925 6700);
FORCEADD OFFPAGE..3
R 2
(150 5725);
FORCEPROP 2 LAST $XR1 151 
J 0
(-280 5725);
DISPLAY 0.638298 (-280 5725);
PAINT MONO (-280 5725);
FORCEPROP 2 LAST $XR0 150 
J 0
(-160 5725);
DISPLAY 0.638298 (-160 5725);
PAINT MONO (-160 5725);
FORCEPROP 2 LAST CDS_LIB standard
J 0
(150 5725);
PAINT MONO (150 5725);
DISPLAY INVISIBLE (150 5725);
FORCEPROP 1 LAST OFFPAGE TRUE
J 2
(-175 5600);
DISPLAY 0.872340 (-175 5600);
DISPLAY INVISIBLE (-175 5600);
FORCEPROP 1 LAST COMMENT_BODY TRUE
J 2
(200 5625);
DISPLAY 0.872340 (200 5625);
PAINT GREEN (200 5625);
DISPLAY INVISIBLE (200 5625);
FORCEPROP 2 LAST PATH I47
J 0
(200 5800);
DISPLAY 0.680851 (200 5800);
DISPLAY INVISIBLE (200 5800);
FORCEADD Q_RES..1
(500 1750);
FORCEPROP 1 LAST LOCATION R1496
J 0
(325 1750);
DISPLAY 0.489362 (325 1750);
PAINT SKYBLUE (325 1750);
FORCEPROP 0 LAST $SEC 1
J 0
(700 1775);
DISPLAY 0.680851 (700 1775);
PAINT MONO (700 1775);
DISPLAY INVISIBLE (700 1775);
FORCEPROP 0 LAST CDS_SEC 1
J 0
(700 1775);
DISPLAY 0.680851 (700 1775);
DISPLAY INVISIBLE (700 1775);
FORCEPROP 1 LASTPIN (400 1750) $PN 1
J 0
(412 1762);
DISPLAY 0.489362 (412 1762);
PAINT MONO (412 1762);
FORCEPROP 1 LASTPIN (600 1750) $PN 2
J 0
(562 1762);
DISPLAY 0.489362 (562 1762);
PAINT MONO (562 1762);
FORCEPROP 1 LAST VALUE 33
J 2
(700 1750);
DISPLAY 0.489362 (700 1750);
PAINT SKYBLUE (700 1750);
FORCEPROP 1 LAST WATTAGE 1/16W
J 2
(900 1675);
DISPLAY 0.489362 (900 1675);
PAINT SKYBLUE (900 1675);
DISPLAY INVISIBLE (900 1675);
FORCEPROP 1 LAST MATERIAL CHIP
J 0
(925 1675);
DISPLAY 0.489362 (925 1675);
PAINT SKYBLUE (925 1675);
DISPLAY INVISIBLE (925 1675);
FORCEPROP 1 LAST TOLERANCE 5%
J 0
(475 1675);
DISPLAY 0.489362 (475 1675);
PAINT SKYBLUE (475 1675);
DISPLAY INVISIBLE (475 1675);
FORCEPROP 1 LAST PACK_TYPE 0402LF
J 0
(550 1675);
DISPLAY 0.489362 (550 1675);
PAINT SKYBLUE (550 1675);
DISPLAY INVISIBLE (550 1675);
FORCEPROP 2 LAST CDS_LIB pure_quanta
J 0
(500 1750);
DISPLAY INVISIBLE (500 1750);
FORCEPROP 1 LAST PART_NUMBER CS03302JB10
J 0
(525 1800);
DISPLAY 0.489362 (525 1800);
PAINT SKYBLUE (525 1800);
DISPLAY INVISIBLE (525 1800);
FORCEPROP 1 LAST PATH I48
J 0
(450 1900);
DISPLAY 0.978723 (450 1900);
PAINT WHITE (450 1900);
DISPLAY INVISIBLE (450 1900);
FORCEADD Q_RES..1
(500 1850);
FORCEPROP 1 LAST LOCATION R1495
J 0
(325 1850);
DISPLAY 0.489362 (325 1850);
PAINT SKYBLUE (325 1850);
FORCEPROP 0 LAST $SEC 1
J 0
(700 1875);
DISPLAY 0.680851 (700 1875);
PAINT MONO (700 1875);
DISPLAY INVISIBLE (700 1875);
FORCEPROP 0 LAST CDS_SEC 1
J 0
(700 1875);
DISPLAY 0.680851 (700 1875);
DISPLAY INVISIBLE (700 1875);
FORCEPROP 1 LASTPIN (400 1850) $PN 1
J 0
(412 1862);
DISPLAY 0.489362 (412 1862);
PAINT MONO (412 1862);
FORCEPROP 1 LASTPIN (600 1850) $PN 2
J 0
(562 1862);
DISPLAY 0.489362 (562 1862);
PAINT MONO (562 1862);
FORCEPROP 1 LAST VALUE 33
J 2
(700 1850);
DISPLAY 0.489362 (700 1850);
PAINT SKYBLUE (700 1850);
FORCEPROP 1 LAST WATTAGE 1/16W
J 2
(900 1775);
DISPLAY 0.489362 (900 1775);
PAINT SKYBLUE (900 1775);
DISPLAY INVISIBLE (900 1775);
FORCEPROP 1 LAST MATERIAL CHIP
J 0
(925 1775);
DISPLAY 0.489362 (925 1775);
PAINT SKYBLUE (925 1775);
DISPLAY INVISIBLE (925 1775);
FORCEPROP 1 LAST TOLERANCE 5%
J 0
(475 1775);
DISPLAY 0.489362 (475 1775);
PAINT SKYBLUE (475 1775);
DISPLAY INVISIBLE (475 1775);
FORCEPROP 1 LAST PACK_TYPE 0402LF
J 0
(550 1775);
DISPLAY 0.489362 (550 1775);
PAINT SKYBLUE (550 1775);
DISPLAY INVISIBLE (550 1775);
FORCEPROP 2 LAST CDS_LIB pure_quanta
J 0
(500 1850);
DISPLAY INVISIBLE (500 1850);
FORCEPROP 1 LAST PART_NUMBER CS03302JB10
J 0
(525 1900);
DISPLAY 0.489362 (525 1900);
PAINT SKYBLUE (525 1900);
DISPLAY INVISIBLE (525 1900);
FORCEPROP 1 LAST PATH I49
J 0
(450 2000);
DISPLAY 0.978723 (450 2000);
PAINT WHITE (450 2000);
DISPLAY INVISIBLE (450 2000);
FORCEADD OFFPAGE..3
(575 2000);
FORCEPROP 2 LAST $XR0 217 
J 0
(789 2000);
DISPLAY 0.638298 (789 2000);
PAINT MONO (789 2000);
FORCEPROP 2 LAST CDS_LIB standard
J 0
(575 2000);
DISPLAY INVISIBLE (575 2000);
FORCEPROP 1 LAST OFFPAGE TRUE
J 0
(900 1875);
DISPLAY 0.872340 (900 1875);
PAINT GREEN (900 1875);
DISPLAY INVISIBLE (900 1875);
FORCEPROP 1 LAST COMMENT_BODY TRUE
J 0
(525 1900);
DISPLAY 0.872340 (525 1900);
PAINT GREEN (525 1900);
DISPLAY INVISIBLE (525 1900);
FORCEPROP 2 LAST PATH I50
J 0
(925 2050);
DISPLAY 0.680851 (925 2050);
DISPLAY INVISIBLE (925 2050);
FORCEADD OFFPAGE..2
(575 2100);
FORCEPROP 2 LAST $XR0 217 
J 0
(764 2100);
DISPLAY 0.638298 (764 2100);
PAINT MONO (764 2100);
FORCEPROP 2 LAST CDS_LIB standard
J 0
(575 2100);
DISPLAY INVISIBLE (575 2100);
FORCEPROP 1 LAST OFFPAGE TRUE
J 0
(900 1975);
DISPLAY 0.872340 (900 1975);
PAINT GREEN (900 1975);
DISPLAY INVISIBLE (900 1975);
FORCEPROP 1 LAST COMMENT_BODY TRUE
J 0
(530 2005);
DISPLAY 0.872340 (530 2005);
PAINT GREEN (530 2005);
DISPLAY INVISIBLE (530 2005);
FORCEPROP 2 LAST PATH I51
J 0
(900 2150);
DISPLAY 0.680851 (900 2150);
DISPLAY INVISIBLE (900 2150);
FORCEADD OFFPAGE..3
(1650 1750);
FORCEPROP 2 LAST $XR0 224 
J 0
(1864 1750);
DISPLAY 0.638298 (1864 1750);
PAINT MONO (1864 1750);
FORCEPROP 2 LAST CDS_LIB standard
J 0
(1650 1750);
DISPLAY INVISIBLE (1650 1750);
FORCEPROP 1 LAST OFFPAGE TRUE
J 0
(1975 1625);
DISPLAY 0.872340 (1975 1625);
PAINT GREEN (1975 1625);
DISPLAY INVISIBLE (1975 1625);
FORCEPROP 1 LAST COMMENT_BODY TRUE
J 0
(1600 1650);
DISPLAY 0.872340 (1600 1650);
PAINT GREEN (1600 1650);
DISPLAY INVISIBLE (1600 1650);
FORCEPROP 2 LAST PATH I54
J 0
(2000 1800);
DISPLAY 0.680851 (2000 1800);
DISPLAY INVISIBLE (2000 1800);
FORCEADD OFFPAGE..2
(1650 1850);
FORCEPROP 2 LAST $XR0 224 
J 0
(1839 1850);
DISPLAY 0.638298 (1839 1850);
PAINT MONO (1839 1850);
FORCEPROP 2 LAST CDS_LIB standard
J 0
(1650 1850);
DISPLAY INVISIBLE (1650 1850);
FORCEPROP 1 LAST OFFPAGE TRUE
J 0
(1975 1725);
DISPLAY 0.872340 (1975 1725);
PAINT GREEN (1975 1725);
DISPLAY INVISIBLE (1975 1725);
FORCEPROP 1 LAST COMMENT_BODY TRUE
J 0
(1605 1755);
DISPLAY 0.872340 (1605 1755);
PAINT GREEN (1605 1755);
DISPLAY INVISIBLE (1605 1755);
FORCEPROP 2 LAST PATH I55
J 0
(1975 1900);
DISPLAY 0.680851 (1975 1900);
DISPLAY INVISIBLE (1975 1900);
FORCEADD Q_RES..1
R 2
(500 4200);
FORCEPROP 1 LAST LOCATION R1453
J 2
(375 4200);
DISPLAY 0.489362 (375 4200);
PAINT SKYBLUE (375 4200);
FORCEPROP 0 LAST $SEC 1
J 0
(375 4250);
DISPLAY 0.680851 (375 4250);
PAINT MONO (375 4250);
DISPLAY INVISIBLE (375 4250);
FORCEPROP 0 LAST CDS_SEC 1
J 0
(375 4250);
DISPLAY 0.680851 (375 4250);
DISPLAY INVISIBLE (375 4250);
FORCEPROP 1 LASTPIN (600 4200) $PN 1
J 2
(588 4212);
DISPLAY 0.489362 (588 4212);
PAINT MONO (588 4212);
FORCEPROP 1 LASTPIN (400 4200) $PN 2
J 2
(438 4212);
DISPLAY 0.489362 (438 4212);
PAINT MONO (438 4212);
FORCEPROP 1 LAST VALUE 0
J 0
(600 4200);
DISPLAY 0.489362 (600 4200);
PAINT SKYBLUE (600 4200);
FORCEPROP 2 LAST CDS_LIB pure_quanta
J 0
(500 4200);
DISPLAY INVISIBLE (500 4200);
FORCEPROP 1 LAST PACK_TYPE 0402LF
J 2
(450 4125);
DISPLAY 0.489362 (450 4125);
PAINT SKYBLUE (450 4125);
DISPLAY INVISIBLE (450 4125);
FORCEPROP 1 LAST TOLERANCE 5%
J 2
(525 4125);
DISPLAY 0.489362 (525 4125);
PAINT SKYBLUE (525 4125);
DISPLAY INVISIBLE (525 4125);
FORCEPROP 1 LAST MATERIAL CHIP
J 2
(75 4125);
DISPLAY 0.489362 (75 4125);
PAINT SKYBLUE (75 4125);
DISPLAY INVISIBLE (75 4125);
FORCEPROP 1 LAST WATTAGE 1/16W
J 0
(100 4125);
DISPLAY 0.489362 (100 4125);
PAINT SKYBLUE (100 4125);
DISPLAY INVISIBLE (100 4125);
FORCEPROP 1 LAST PART_NUMBER CS00002JB13
J 2
(475 4250);
DISPLAY 0.489362 (475 4250);
PAINT SKYBLUE (475 4250);
DISPLAY INVISIBLE (475 4250);
FORCEPROP 1 LAST PATH I56
J 2
(550 4350);
DISPLAY 0.978723 (550 4350);
PAINT WHITE (550 4350);
DISPLAY INVISIBLE (550 4350);
FORCEADD Q_RES..1
R 2
(500 4300);
FORCEPROP 1 LAST LOCATION R1447
J 2
(375 4300);
DISPLAY 0.489362 (375 4300);
PAINT SKYBLUE (375 4300);
FORCEPROP 0 LAST $SEC 1
J 0
(375 4350);
DISPLAY 0.680851 (375 4350);
PAINT MONO (375 4350);
DISPLAY INVISIBLE (375 4350);
FORCEPROP 0 LAST CDS_SEC 1
J 0
(375 4350);
DISPLAY 0.680851 (375 4350);
DISPLAY INVISIBLE (375 4350);
FORCEPROP 1 LASTPIN (600 4300) $PN 1
J 2
(588 4312);
DISPLAY 0.489362 (588 4312);
PAINT MONO (588 4312);
FORCEPROP 1 LASTPIN (400 4300) $PN 2
J 2
(438 4312);
DISPLAY 0.489362 (438 4312);
PAINT MONO (438 4312);
FORCEPROP 1 LAST VALUE 0
J 0
(600 4300);
DISPLAY 0.489362 (600 4300);
PAINT SKYBLUE (600 4300);
FORCEPROP 2 LAST CDS_LIB pure_quanta
J 0
(500 4300);
DISPLAY INVISIBLE (500 4300);
FORCEPROP 1 LAST PACK_TYPE 0402LF
J 2
(450 4225);
DISPLAY 0.489362 (450 4225);
PAINT SKYBLUE (450 4225);
DISPLAY INVISIBLE (450 4225);
FORCEPROP 1 LAST TOLERANCE 5%
J 2
(525 4225);
DISPLAY 0.489362 (525 4225);
PAINT SKYBLUE (525 4225);
DISPLAY INVISIBLE (525 4225);
FORCEPROP 1 LAST MATERIAL CHIP
J 2
(75 4225);
DISPLAY 0.489362 (75 4225);
PAINT SKYBLUE (75 4225);
DISPLAY INVISIBLE (75 4225);
FORCEPROP 1 LAST WATTAGE 1/16W
J 0
(100 4225);
DISPLAY 0.489362 (100 4225);
PAINT SKYBLUE (100 4225);
DISPLAY INVISIBLE (100 4225);
FORCEPROP 1 LAST PART_NUMBER CS00002JB13
J 2
(475 4350);
DISPLAY 0.489362 (475 4350);
PAINT SKYBLUE (475 4350);
DISPLAY INVISIBLE (475 4350);
FORCEPROP 1 LAST PATH I57
J 2
(550 4450);
DISPLAY 0.978723 (550 4450);
PAINT WHITE (550 4450);
DISPLAY INVISIBLE (550 4450);
FORCEADD OFFPAGE..2
(825 4550);
FORCEPROP 2 LAST $XR1 151 
J 0
(1104 4550);
DISPLAY 0.638298 (1104 4550);
PAINT MONO (1104 4550);
FORCEPROP 2 LAST $XR0 28 
J 0
(1014 4550);
DISPLAY 0.638298 (1014 4550);
PAINT MONO (1014 4550);
FORCEPROP 2 LAST CDS_LIB standard
J 0
(825 4550);
DISPLAY INVISIBLE (825 4550);
FORCEPROP 1 LAST OFFPAGE TRUE
J 0
(1150 4425);
DISPLAY 0.872340 (1150 4425);
PAINT GREEN (1150 4425);
DISPLAY INVISIBLE (1150 4425);
FORCEPROP 1 LAST COMMENT_BODY TRUE
J 0
(780 4455);
DISPLAY 0.872340 (780 4455);
PAINT PEACH (780 4455);
DISPLAY INVISIBLE (780 4455);
FORCEPROP 2 LAST PATH I58
J 0
(1125 4600);
DISPLAY 0.680851 (1125 4600);
DISPLAY INVISIBLE (1125 4600);
FORCEADD OFFPAGE..2
(825 4600);
FORCEPROP 2 LAST $XR1 151 
J 0
(1104 4600);
DISPLAY 0.638298 (1104 4600);
PAINT MONO (1104 4600);
FORCEPROP 2 LAST $XR0 28 
J 0
(1014 4600);
DISPLAY 0.638298 (1014 4600);
PAINT MONO (1014 4600);
FORCEPROP 2 LAST CDS_LIB standard
J 0
(825 4600);
DISPLAY INVISIBLE (825 4600);
FORCEPROP 1 LAST OFFPAGE TRUE
J 0
(1150 4475);
DISPLAY 0.872340 (1150 4475);
PAINT GREEN (1150 4475);
DISPLAY INVISIBLE (1150 4475);
FORCEPROP 1 LAST COMMENT_BODY TRUE
J 0
(780 4505);
DISPLAY 0.872340 (780 4505);
PAINT PEACH (780 4505);
DISPLAY INVISIBLE (780 4505);
FORCEPROP 2 LAST PATH I59
J 0
(1125 4650);
DISPLAY 0.680851 (1125 4650);
DISPLAY INVISIBLE (1125 4650);
FORCEADD OFFPAGE..3
(1400 4200);
FORCEPROP 2 LAST $XR0 28 
J 0
(1614 4200);
DISPLAY 0.638298 (1614 4200);
PAINT MONO (1614 4200);
FORCEPROP 2 LAST $XR1 151 
J 0
(1704 4200);
DISPLAY 0.638298 (1704 4200);
PAINT MONO (1704 4200);
FORCEPROP 2 LAST CDS_LIB standard
J 0
(1400 4200);
DISPLAY INVISIBLE (1400 4200);
FORCEPROP 1 LAST OFFPAGE TRUE
J 0
(1725 4075);
DISPLAY 0.872340 (1725 4075);
PAINT GREEN (1725 4075);
DISPLAY INVISIBLE (1725 4075);
FORCEPROP 1 LAST COMMENT_BODY TRUE
J 0
(1350 4100);
DISPLAY 0.872340 (1350 4100);
PAINT PEACH (1350 4100);
DISPLAY INVISIBLE (1350 4100);
FORCEPROP 2 LAST PATH I60
J 0
(1725 4250);
DISPLAY 0.680851 (1725 4250);
DISPLAY INVISIBLE (1725 4250);
FORCEADD OFFPAGE..1
R 2
(1425 4300);
FORCEPROP 2 LAST $XR1 151 
J 0
(1701 4300);
DISPLAY 0.638298 (1701 4300);
PAINT MONO (1701 4300);
FORCEPROP 2 LAST $XR0 28 
J 0
(1611 4300);
DISPLAY 0.638298 (1611 4300);
PAINT MONO (1611 4300);
FORCEPROP 2 LAST CDS_LIB standard
J 0
(1425 4300);
DISPLAY INVISIBLE (1425 4300);
FORCEPROP 1 LAST OFFPAGE TRUE
J 2
(1100 4175);
DISPLAY 0.872340 (1100 4175);
PAINT GREEN (1100 4175);
DISPLAY INVISIBLE (1100 4175);
FORCEPROP 1 LAST COMMENT_BODY TRUE
J 2
(1300 4200);
DISPLAY 0.872340 (1300 4200);
PAINT GREEN (1300 4200);
DISPLAY INVISIBLE (1300 4200);
FORCEPROP 2 LAST PATH I61
J 0
(1725 4350);
DISPLAY 0.680851 (1725 4350);
DISPLAY INVISIBLE (1725 4350);
FORCEADD OFFPAGE..6
(2775 2125);
FORCEPROP 2 LAST $XR1 248 
J 0
(2375 2125);
DISPLAY 0.638298 (2375 2125);
PAINT MONO (2375 2125);
FORCEPROP 2 LAST $XR0 150 
J 0
(2495 2125);
DISPLAY 0.638298 (2495 2125);
PAINT MONO (2495 2125);
FORCEPROP 2 LAST CDS_LIB standard
J 0
(2775 2125);
DISPLAY INVISIBLE (2775 2125);
FORCEPROP 1 LAST OFFPAGE TRUE
J 0
(3100 2000);
DISPLAY 0.872340 (3100 2000);
PAINT GREEN (3100 2000);
DISPLAY INVISIBLE (3100 2000);
FORCEPROP 1 LAST COMMENT_BODY TRUE
J 0
(2875 2050);
DISPLAY 0.872340 (2875 2050);
PAINT PEACH (2875 2050);
DISPLAY INVISIBLE (2875 2050);
FORCEPROP 2 LAST PATH I64
J 0
(2500 2175);
DISPLAY 0.680851 (2500 2175);
DISPLAY INVISIBLE (2500 2175);
FORCEADD OFFPAGE..6
(2775 2075);
FORCEPROP 2 LAST $XR1 248 
J 0
(2375 2075);
DISPLAY 0.638298 (2375 2075);
PAINT MONO (2375 2075);
FORCEPROP 2 LAST $XR0 150 
J 0
(2495 2075);
DISPLAY 0.638298 (2495 2075);
PAINT MONO (2495 2075);
FORCEPROP 2 LAST CDS_LIB standard
J 0
(2775 2075);
DISPLAY INVISIBLE (2775 2075);
FORCEPROP 1 LAST OFFPAGE TRUE
J 0
(3100 1950);
DISPLAY 0.872340 (3100 1950);
PAINT GREEN (3100 1950);
DISPLAY INVISIBLE (3100 1950);
FORCEPROP 1 LAST COMMENT_BODY TRUE
J 0
(2875 2000);
DISPLAY 0.872340 (2875 2000);
PAINT PEACH (2875 2000);
DISPLAY INVISIBLE (2875 2000);
FORCEPROP 2 LAST PATH I65
J 0
(2500 2125);
DISPLAY 0.680851 (2500 2125);
DISPLAY INVISIBLE (2500 2125);
FORCEADD UNIVERSAL_GND..1
R 2
(4050 1075);
FORCEPROP 3 LASTPIN (4050 1125) SIG_NAME GND\g
J 0
(4060 1135);
DISPLAY 0.659574 (4060 1135);
PAINT MONO (4060 1135);
DISPLAY INVISIBLE (4060 1135);
FORCEPROP 2 LAST CDS_LIB pure_quanta_power
J 0
(4050 1075);
DISPLAY INVISIBLE (4050 1075);
FORCEPROP 1 LAST HDL_POWER GND
J 1
(4025 1000);
DISPLAY 0.872340 (4025 1000);
PAINT GREEN (4025 1000);
DISPLAY INVISIBLE (4025 1000);
FORCEPROP 1 LAST PATH I66
J 2
(3975 1075);
DISPLAY 0.872340 (3975 1075);
PAINT AQUA (3975 1075);
DISPLAY INVISIBLE (3975 1075);
FORCEADD OFFPAGE..2
R 2
(3925 1550);
FORCEPROP 2 LAST $XR1 164 
J 0
(3550 1550);
DISPLAY 0.638298 (3550 1550);
PAINT MONO (3550 1550);
FORCEPROP 2 LAST $XR0 150 
J 0
(3670 1550);
DISPLAY 0.638298 (3670 1550);
PAINT MONO (3670 1550);
FORCEPROP 2 LAST CDS_LIB standard
J 2
(3925 1550);
DISPLAY INVISIBLE (3925 1550);
FORCEPROP 1 LAST OFFPAGE TRUE
J 2
(3600 1425);
DISPLAY 0.872340 (3600 1425);
PAINT GREEN (3600 1425);
DISPLAY INVISIBLE (3600 1425);
FORCEPROP 1 LAST COMMENT_BODY TRUE
J 2
(3970 1455);
DISPLAY 0.872340 (3970 1455);
PAINT GREEN (3970 1455);
DISPLAY INVISIBLE (3970 1455);
FORCEPROP 2 LAST PATH I67
J 0
(3675 1600);
DISPLAY 0.680851 (3675 1600);
DISPLAY INVISIBLE (3675 1600);
FORCEADD OFFPAGE..1
(3925 1600);
FORCEPROP 2 LAST $XR1 150 
J 0
(3553 1600);
DISPLAY 0.638298 (3553 1600);
PAINT MONO (3553 1600);
FORCEPROP 2 LAST $XR0 164 
J 0
(3673 1600);
DISPLAY 0.638298 (3673 1600);
PAINT MONO (3673 1600);
FORCEPROP 2 LAST CDS_LIB standard
J 2
(3925 1600);
DISPLAY INVISIBLE (3925 1600);
FORCEPROP 1 LAST OFFPAGE TRUE
J 0
(4250 1475);
DISPLAY 0.872340 (4250 1475);
PAINT GREEN (4250 1475);
DISPLAY INVISIBLE (4250 1475);
FORCEPROP 1 LAST COMMENT_BODY TRUE
J 0
(4050 1500);
DISPLAY 0.872340 (4050 1500);
PAINT GREEN (4050 1500);
DISPLAY INVISIBLE (4050 1500);
FORCEPROP 2 LAST PATH I68
J 0
(3675 1650);
DISPLAY 0.680851 (3675 1650);
DISPLAY INVISIBLE (3675 1650);
FORCEADD Q_CAP..1
(4050 1275);
FORCEPROP 1 LAST LOCATION C62
J 0
(4100 1375);
DISPLAY 0.489362 (4100 1375);
PAINT SKYBLUE (4100 1375);
FORCEPROP 0 LAST $SEC 1
J 0
(4100 1400);
DISPLAY 0.680851 (4100 1400);
PAINT MONO (4100 1400);
DISPLAY INVISIBLE (4100 1400);
FORCEPROP 0 LAST CDS_SEC 1
J 0
(4100 1400);
DISPLAY 1.021277 (4100 1400);
DISPLAY INVISIBLE (4100 1400);
FORCEPROP 1 LASTPIN (4050 1375) $PN 1
J 0
(4060 1355);
DISPLAY 0.489362 (4060 1355);
PAINT MONO (4060 1355);
FORCEPROP 1 LASTPIN (4050 1175) $PN 2
J 0
(4060 1155);
DISPLAY 0.489362 (4060 1155);
PAINT MONO (4060 1155);
FORCEPROP 1 LAST PACK_TYPE C0402
J 0
(4100 1175);
DISPLAY 0.489362 (4100 1175);
PAINT SKYBLUE (4100 1175);
FORCEPROP 1 LAST TOLERANCE 5%
J 0
(4100 1225);
DISPLAY 0.489362 (4100 1225);
PAINT SKYBLUE (4100 1225);
FORCEPROP 1 LAST VALUE 220PF
J 0
(4100 1325);
DISPLAY 0.489362 (4100 1325);
PAINT SKYBLUE (4100 1325);
FORCEPROP 1 LAST VOLTAGE 50V
J 0
(4100 1275);
DISPLAY 0.489362 (4100 1275);
PAINT SKYBLUE (4100 1275);
FORCEPROP 2 LAST CDS_LIB pure_quanta
J 0
(4050 1275);
DISPLAY INVISIBLE (4050 1275);
FORCEPROP 1 LAST MATERIAL C0G
J 0
(4100 1175);
DISPLAY 0.404255 (4100 1175);
PAINT SKYBLUE (4100 1175);
DISPLAY INVISIBLE (4100 1175);
FORCEPROP 1 LAST PART_NUMBER CH12206JB00
J 0
(4100 1125);
DISPLAY 0.404255 (4100 1125);
PAINT SKYBLUE (4100 1125);
DISPLAY INVISIBLE (4100 1125);
FORCEPROP 1 LAST PATH I69
J 0
(4100 1425);
DISPLAY 0.978723 (4100 1425);
PAINT WHITE (4100 1425);
DISPLAY INVISIBLE (4100 1425);
FORCEADD OFFPAGE..6
(2775 2375);
FORCEPROP 2 LAST $XR1 248 
J 0
(2375 2375);
DISPLAY 0.638298 (2375 2375);
PAINT MONO (2375 2375);
FORCEPROP 2 LAST $XR0 150 
J 0
(2495 2375);
DISPLAY 0.638298 (2495 2375);
PAINT MONO (2495 2375);
FORCEPROP 2 LAST CDS_LIB standard
J 0
(2775 2375);
DISPLAY INVISIBLE (2775 2375);
FORCEPROP 1 LAST OFFPAGE TRUE
J 0
(3100 2250);
DISPLAY 0.872340 (3100 2250);
PAINT GREEN (3100 2250);
DISPLAY INVISIBLE (3100 2250);
FORCEPROP 1 LAST COMMENT_BODY TRUE
J 0
(2875 2300);
DISPLAY 0.872340 (2875 2300);
PAINT PEACH (2875 2300);
DISPLAY INVISIBLE (2875 2300);
FORCEPROP 2 LAST PATH I70
J 0
(2500 2425);
DISPLAY 0.680851 (2500 2425);
DISPLAY INVISIBLE (2500 2425);
FORCEADD OFFPAGE..6
(2775 2425);
FORCEPROP 2 LAST $XR1 248 
J 0
(2375 2425);
DISPLAY 0.638298 (2375 2425);
PAINT MONO (2375 2425);
FORCEPROP 2 LAST $XR0 150 
J 0
(2495 2425);
DISPLAY 0.638298 (2495 2425);
PAINT MONO (2495 2425);
FORCEPROP 2 LAST CDS_LIB standard
J 0
(2775 2425);
DISPLAY INVISIBLE (2775 2425);
FORCEPROP 1 LAST OFFPAGE TRUE
J 0
(3100 2300);
DISPLAY 0.872340 (3100 2300);
PAINT GREEN (3100 2300);
DISPLAY INVISIBLE (3100 2300);
FORCEPROP 1 LAST COMMENT_BODY TRUE
J 0
(2875 2350);
DISPLAY 0.872340 (2875 2350);
PAINT PEACH (2875 2350);
DISPLAY INVISIBLE (2875 2350);
FORCEPROP 2 LAST PATH I71
J 0
(2500 2475);
DISPLAY 0.680851 (2500 2475);
DISPLAY INVISIBLE (2500 2475);
FORCEADD OFFPAGE..5
(2775 2700);
FORCEPROP 2 LAST $XR1 249 
J 0
(2400 2700);
DISPLAY 0.638298 (2400 2700);
PAINT MONO (2400 2700);
FORCEPROP 2 LAST $XR0 150 
J 0
(2520 2700);
DISPLAY 0.638298 (2520 2700);
PAINT MONO (2520 2700);
FORCEPROP 2 LAST CDS_LIB standard
J 0
(2775 2700);
DISPLAY INVISIBLE (2775 2700);
FORCEPROP 1 LAST OFFPAGE TRUE
J 0
(3100 2575);
DISPLAY 0.872340 (3100 2575);
PAINT GREEN (3100 2575);
DISPLAY INVISIBLE (3100 2575);
FORCEPROP 1 LAST COMMENT_BODY TRUE
J 0
(2875 2625);
DISPLAY 0.872340 (2875 2625);
PAINT PEACH (2875 2625);
DISPLAY INVISIBLE (2875 2625);
FORCEPROP 2 LAST PATH I72
J 0
(2500 2750);
DISPLAY 0.680851 (2500 2750);
DISPLAY INVISIBLE (2500 2750);
FORCEADD OFFPAGE..5
(2775 2650);
FORCEPROP 2 LAST $XR1 249 
J 0
(2400 2650);
DISPLAY 0.638298 (2400 2650);
PAINT MONO (2400 2650);
FORCEPROP 2 LAST $XR0 150 
J 0
(2520 2650);
DISPLAY 0.638298 (2520 2650);
PAINT MONO (2520 2650);
FORCEPROP 2 LAST CDS_LIB standard
J 0
(2775 2650);
DISPLAY INVISIBLE (2775 2650);
FORCEPROP 1 LAST OFFPAGE TRUE
J 0
(3100 2525);
DISPLAY 0.872340 (3100 2525);
PAINT GREEN (3100 2525);
DISPLAY INVISIBLE (3100 2525);
FORCEPROP 1 LAST COMMENT_BODY TRUE
J 0
(2875 2575);
DISPLAY 0.872340 (2875 2575);
PAINT PEACH (2875 2575);
DISPLAY INVISIBLE (2875 2575);
FORCEPROP 2 LAST PATH I73
J 0
(2500 2700);
DISPLAY 0.680851 (2500 2700);
DISPLAY INVISIBLE (2500 2700);
FORCEADD OFFPAGE..5
(2775 3050);
FORCEPROP 2 LAST $XR1 249 
J 0
(2400 3050);
DISPLAY 0.638298 (2400 3050);
PAINT MONO (2400 3050);
FORCEPROP 2 LAST $XR0 150 
J 0
(2520 3050);
DISPLAY 0.638298 (2520 3050);
PAINT MONO (2520 3050);
FORCEPROP 2 LAST CDS_LIB standard
J 0
(2775 3050);
DISPLAY INVISIBLE (2775 3050);
FORCEPROP 1 LAST OFFPAGE TRUE
J 0
(3100 2925);
DISPLAY 0.872340 (3100 2925);
PAINT GREEN (3100 2925);
DISPLAY INVISIBLE (3100 2925);
FORCEPROP 1 LAST COMMENT_BODY TRUE
J 0
(2875 2975);
DISPLAY 0.872340 (2875 2975);
PAINT PEACH (2875 2975);
DISPLAY INVISIBLE (2875 2975);
FORCEPROP 2 LAST PATH I74
J 0
(2500 3100);
DISPLAY 0.680851 (2500 3100);
DISPLAY INVISIBLE (2500 3100);
FORCEADD OFFPAGE..5
(2775 3100);
FORCEPROP 2 LAST $XR1 249 
J 0
(2400 3100);
DISPLAY 0.638298 (2400 3100);
PAINT MONO (2400 3100);
FORCEPROP 2 LAST $XR0 150 
J 0
(2520 3100);
DISPLAY 0.638298 (2520 3100);
PAINT MONO (2520 3100);
FORCEPROP 2 LAST CDS_LIB standard
J 0
(2775 3100);
DISPLAY INVISIBLE (2775 3100);
FORCEPROP 1 LAST OFFPAGE TRUE
J 0
(3100 2975);
DISPLAY 0.872340 (3100 2975);
PAINT GREEN (3100 2975);
DISPLAY INVISIBLE (3100 2975);
FORCEPROP 1 LAST COMMENT_BODY TRUE
J 0
(2875 3025);
DISPLAY 0.872340 (2875 3025);
PAINT PEACH (2875 3025);
DISPLAY INVISIBLE (2875 3025);
FORCEPROP 2 LAST PATH I75
J 0
(2500 3150);
DISPLAY 0.680851 (2500 3150);
DISPLAY INVISIBLE (2500 3150);
FORCEADD OFFPAGE..5
(2775 3425);
FORCEPROP 2 LAST $XR1 151 
J 0
(2400 3425);
DISPLAY 0.638298 (2400 3425);
PAINT MONO (2400 3425);
FORCEPROP 2 LAST $XR0 150 
J 0
(2520 3425);
DISPLAY 0.638298 (2520 3425);
PAINT MONO (2520 3425);
FORCEPROP 2 LAST CDS_LIB standard
J 0
(2775 3425);
DISPLAY INVISIBLE (2775 3425);
FORCEPROP 1 LAST OFFPAGE TRUE
J 0
(3100 3300);
DISPLAY 0.872340 (3100 3300);
PAINT GREEN (3100 3300);
DISPLAY INVISIBLE (3100 3300);
FORCEPROP 1 LAST COMMENT_BODY TRUE
J 0
(2875 3350);
DISPLAY 0.872340 (2875 3350);
PAINT PEACH (2875 3350);
DISPLAY INVISIBLE (2875 3350);
FORCEPROP 2 LAST PATH I76
J 0
(2500 3475);
DISPLAY 0.680851 (2500 3475);
DISPLAY INVISIBLE (2500 3475);
FORCEADD OFFPAGE..5
(2775 3475);
FORCEPROP 2 LAST $XR1 151 
J 0
(2400 3475);
DISPLAY 0.638298 (2400 3475);
PAINT MONO (2400 3475);
FORCEPROP 2 LAST $XR0 150 
J 0
(2520 3475);
DISPLAY 0.638298 (2520 3475);
PAINT MONO (2520 3475);
FORCEPROP 2 LAST CDS_LIB standard
J 0
(2775 3475);
DISPLAY INVISIBLE (2775 3475);
FORCEPROP 1 LAST OFFPAGE TRUE
J 0
(3100 3350);
DISPLAY 0.872340 (3100 3350);
PAINT GREEN (3100 3350);
DISPLAY INVISIBLE (3100 3350);
FORCEPROP 1 LAST COMMENT_BODY TRUE
J 0
(2875 3400);
DISPLAY 0.872340 (2875 3400);
PAINT PEACH (2875 3400);
DISPLAY INVISIBLE (2875 3400);
FORCEPROP 2 LAST PATH I77
J 0
(2500 3525);
DISPLAY 0.680851 (2500 3525);
DISPLAY INVISIBLE (2500 3525);
FORCEADD OFFPAGE..5
(2775 3725);
FORCEPROP 2 LAST $XR0 150 
J 0
(2520 3725);
DISPLAY 0.638298 (2520 3725);
PAINT MONO (2520 3725);
FORCEPROP 2 LAST $XR1 249 
J 0
(2400 3725);
DISPLAY 0.638298 (2400 3725);
PAINT MONO (2400 3725);
FORCEPROP 2 LAST CDS_LIB standard
J 0
(2775 3725);
DISPLAY INVISIBLE (2775 3725);
FORCEPROP 1 LAST OFFPAGE TRUE
J 0
(3100 3600);
DISPLAY 0.872340 (3100 3600);
PAINT GREEN (3100 3600);
DISPLAY INVISIBLE (3100 3600);
FORCEPROP 1 LAST COMMENT_BODY TRUE
J 0
(2875 3650);
DISPLAY 0.872340 (2875 3650);
PAINT PEACH (2875 3650);
DISPLAY INVISIBLE (2875 3650);
FORCEPROP 2 LAST PATH I78
J 0
(2500 3775);
DISPLAY 0.680851 (2500 3775);
DISPLAY INVISIBLE (2500 3775);
FORCEADD OFFPAGE..5
(2775 3775);
FORCEPROP 2 LAST $XR0 150 
J 0
(2520 3775);
DISPLAY 0.638298 (2520 3775);
PAINT MONO (2520 3775);
FORCEPROP 2 LAST $XR1 249 
J 0
(2400 3775);
DISPLAY 0.638298 (2400 3775);
PAINT MONO (2400 3775);
FORCEPROP 2 LAST CDS_LIB standard
J 0
(2775 3775);
DISPLAY INVISIBLE (2775 3775);
FORCEPROP 1 LAST OFFPAGE TRUE
J 0
(3100 3650);
DISPLAY 0.872340 (3100 3650);
PAINT GREEN (3100 3650);
DISPLAY INVISIBLE (3100 3650);
FORCEPROP 1 LAST COMMENT_BODY TRUE
J 0
(2875 3700);
DISPLAY 0.872340 (2875 3700);
PAINT PEACH (2875 3700);
DISPLAY INVISIBLE (2875 3700);
FORCEPROP 2 LAST PATH I79
J 0
(2500 3825);
DISPLAY 0.680851 (2500 3825);
DISPLAY INVISIBLE (2500 3825);
FORCEADD OFFPAGE..1
(175 5775);
FORCEPROP 2 LAST $XR1 151 
J 0
(-227 5775);
DISPLAY 0.638298 (-227 5775);
PAINT MONO (-227 5775);
FORCEPROP 2 LAST $XR0 150 
J 0
(-107 5775);
DISPLAY 0.638298 (-107 5775);
PAINT MONO (-107 5775);
FORCEPROP 2 LAST CDS_LIB standard
J 0
(175 5775);
PAINT MONO (175 5775);
DISPLAY INVISIBLE (175 5775);
FORCEPROP 1 LAST OFFPAGE TRUE
J 0
(500 5650);
DISPLAY 0.872340 (500 5650);
PAINT GREEN (500 5650);
DISPLAY INVISIBLE (500 5650);
FORCEPROP 1 LAST COMMENT_BODY TRUE
J 0
(300 5675);
DISPLAY 0.872340 (300 5675);
PAINT GREEN (300 5675);
DISPLAY INVISIBLE (300 5675);
FORCEPROP 2 LAST PATH I80
J 0
(225 5850);
DISPLAY 0.680851 (225 5850);
DISPLAY INVISIBLE (225 5850);
FORCEADD Q_RES..1
(1750 5775);
FORCEPROP 1 LAST LOCATION R3340
J 0
(1500 5775);
DISPLAY 0.808511 (1500 5775);
FORCEPROP 0 LAST $SEC 1
J 0
(1925 5925);
DISPLAY 0.680851 (1925 5925);
PAINT MONO (1925 5925);
DISPLAY INVISIBLE (1925 5925);
FORCEPROP 0 LAST CDS_SEC 1
J 0
(1925 5925);
DISPLAY 1.021277 (1925 5925);
DISPLAY INVISIBLE (1925 5925);
FORCEPROP 1 LASTPIN (1650 5775) $PN 1
J 0
(1662 5787);
DISPLAY 0.787234 (1662 5787);
FORCEPROP 1 LASTPIN (1850 5775) $PN 2
J 0
(1812 5787);
DISPLAY 0.787234 (1812 5787);
FORCEPROP 1 LAST PACK_TYPE 0402LF
J 0
(1625 5900);
DISPLAY 0.510638 (1625 5900);
FORCEPROP 1 LAST VALUE 33.2
J 2
(1950 5775);
DISPLAY 0.510638 (1950 5775);
FORCEPROP 1 LAST MATERIAL CHIP
J 0
(2050 5775);
DISPLAY 0.510638 (2050 5775);
FORCEPROP 1 LAST TOLERANCE 1%
J 0
(1975 5775);
DISPLAY 0.510638 (1975 5775);
FORCEPROP 1 LAST WATTAGE 1/16W
J 2
(1925 5900);
DISPLAY 0.510638 (1925 5900);
FORCEPROP 2 LAST CDS_LIB pure_quanta
J 0
(1750 5775);
DISPLAY INVISIBLE (1750 5775);
FORCEPROP 1 LAST PART_NUMBER CS03322FB03
J 0
(1625 5850);
DISPLAY 0.510638 (1625 5850);
DISPLAY INVISIBLE (1625 5850);
FORCEPROP 1 LAST PATH I81
J 0
(1700 5925);
DISPLAY 0.978723 (1700 5925);
PAINT WHITE (1700 5925);
DISPLAY INVISIBLE (1700 5925);
FORCEADD Q_RES..1
(1750 5725);
FORCEPROP 1 LAST LOCATION R3341
J 0
(1500 5725);
DISPLAY 0.808511 (1500 5725);
FORCEPROP 0 LAST $SEC 1
J 0
(1500 5775);
DISPLAY 0.680851 (1500 5775);
PAINT MONO (1500 5775);
DISPLAY INVISIBLE (1500 5775);
FORCEPROP 0 LAST CDS_SEC 1
J 0
(1500 5775);
DISPLAY 1.021277 (1500 5775);
DISPLAY INVISIBLE (1500 5775);
FORCEPROP 1 LASTPIN (1650 5725) $PN 1
J 0
(1662 5737);
DISPLAY 0.787234 (1662 5737);
FORCEPROP 1 LASTPIN (1850 5725) $PN 2
J 0
(1812 5737);
DISPLAY 0.787234 (1812 5737);
FORCEPROP 1 LAST VALUE 33.2
J 2
(1950 5725);
DISPLAY 0.510638 (1950 5725);
FORCEPROP 1 LAST TOLERANCE 1%
J 0
(1975 5725);
DISPLAY 0.510638 (1975 5725);
FORCEPROP 1 LAST MATERIAL CHIP
J 0
(2050 5725);
DISPLAY 0.510638 (2050 5725);
FORCEPROP 2 LAST CDS_LIB pure_quanta
J 0
(1750 5725);
DISPLAY INVISIBLE (1750 5725);
FORCEPROP 1 LAST WATTAGE 1/16W
J 2
(1950 5825);
DISPLAY 0.638298 (1950 5825);
DISPLAY INVISIBLE (1950 5825);
FORCEPROP 1 LAST PACK_TYPE 0402LF
J 0
(2100 5725);
DISPLAY 0.638298 (2100 5725);
DISPLAY INVISIBLE (2100 5725);
FORCEPROP 1 LAST PART_NUMBER CS03322FB03
J 0
(1625 5775);
DISPLAY 0.638298 (1625 5775);
DISPLAY INVISIBLE (1625 5775);
FORCEPROP 1 LAST PATH I82
J 0
(1700 5875);
DISPLAY 0.978723 (1700 5875);
PAINT WHITE (1700 5875);
DISPLAY INVISIBLE (1700 5875);
FORCEADD Q_RES..1
(1950 6075);
FORCEPROP 1 LAST LOCATION R4151
J 0
(1700 6075);
DISPLAY 0.638298 (1700 6075);
FORCEPROP 0 LAST $SEC 1
J 0
(2125 6225);
DISPLAY 0.680851 (2125 6225);
PAINT MONO (2125 6225);
DISPLAY INVISIBLE (2125 6225);
FORCEPROP 0 LAST CDS_SEC 1
J 0
(2125 6225);
DISPLAY 1.021277 (2125 6225);
DISPLAY INVISIBLE (2125 6225);
FORCEPROP 1 LASTPIN (1850 6075) $PN 1
J 0
(1862 6087);
DISPLAY 0.787234 (1862 6087);
PAINT MONO (1862 6087);
FORCEPROP 1 LASTPIN (2050 6075) $PN 2
J 0
(2012 6087);
DISPLAY 0.787234 (2012 6087);
PAINT MONO (2012 6087);
FORCEPROP 1 LAST TOLERANCE 1%
J 0
(2175 6075);
DISPLAY 0.510638 (2175 6075);
FORCEPROP 1 LAST VALUE 33.2
J 2
(2150 6075);
DISPLAY 0.510638 (2150 6075);
FORCEPROP 1 LAST WATTAGE 1/16W
J 2
(2125 6200);
DISPLAY 0.510638 (2125 6200);
FORCEPROP 1 LAST MATERIAL CHIP
J 0
(2250 6075);
DISPLAY 0.510638 (2250 6075);
FORCEPROP 1 LAST PACK_TYPE 0402LF
J 0
(1825 6200);
DISPLAY 0.510638 (1825 6200);
FORCEPROP 2 LAST CDS_LIB pure_quanta
J 0
(1950 6075);
DISPLAY INVISIBLE (1950 6075);
FORCEPROP 1 LAST PART_NUMBER CS03322FB03
J 0
(1825 6150);
DISPLAY 0.510638 (1825 6150);
DISPLAY INVISIBLE (1825 6150);
FORCEPROP 1 LAST PATH I83
J 0
(1900 6225);
DISPLAY 0.978723 (1900 6225);
PAINT WHITE (1900 6225);
DISPLAY INVISIBLE (1900 6225);
FORCEADD Q_RES..1
(1950 6025);
FORCEPROP 1 LAST LOCATION R4152
J 0
(1700 6025);
DISPLAY 0.638298 (1700 6025);
FORCEPROP 0 LAST $SEC 1
J 0
(1775 6075);
DISPLAY 0.680851 (1775 6075);
PAINT MONO (1775 6075);
DISPLAY INVISIBLE (1775 6075);
FORCEPROP 0 LAST CDS_SEC 1
J 0
(1775 6075);
DISPLAY 1.021277 (1775 6075);
DISPLAY INVISIBLE (1775 6075);
FORCEPROP 1 LASTPIN (1850 6025) $PN 1
J 0
(1862 6037);
DISPLAY 0.787234 (1862 6037);
PAINT MONO (1862 6037);
FORCEPROP 1 LASTPIN (2050 6025) $PN 2
J 0
(2012 6037);
DISPLAY 0.787234 (2012 6037);
PAINT MONO (2012 6037);
FORCEPROP 1 LAST TOLERANCE 1%
J 0
(2175 6025);
DISPLAY 0.510638 (2175 6025);
FORCEPROP 1 LAST VALUE 33.2
J 2
(2150 6025);
DISPLAY 0.510638 (2150 6025);
FORCEPROP 1 LAST MATERIAL CHIP
J 0
(2250 6025);
DISPLAY 0.510638 (2250 6025);
FORCEPROP 2 LAST CDS_LIB pure_quanta
J 0
(1950 6025);
DISPLAY INVISIBLE (1950 6025);
FORCEPROP 1 LAST PACK_TYPE 0402LF
J 0
(2300 6025);
DISPLAY 0.638298 (2300 6025);
DISPLAY INVISIBLE (2300 6025);
FORCEPROP 1 LAST WATTAGE 1/16W
J 2
(2150 6125);
DISPLAY 0.638298 (2150 6125);
DISPLAY INVISIBLE (2150 6125);
FORCEPROP 1 LAST PART_NUMBER CS03322FB03
J 0
(1825 6075);
DISPLAY 0.638298 (1825 6075);
DISPLAY INVISIBLE (1825 6075);
FORCEPROP 1 LAST PATH I84
J 0
(1900 6175);
DISPLAY 0.978723 (1900 6175);
PAINT WHITE (1900 6175);
DISPLAY INVISIBLE (1900 6175);
FORCEADD OFFPAGE..1
(200 6350);
FORCEPROP 2 LAST $XR0 150 
J 0
(-52 6350);
DISPLAY 0.638298 (-52 6350);
PAINT MONO (-52 6350);
FORCEPROP 2 LAST $XR1 151 
J 0
(-172 6350);
DISPLAY 0.638298 (-172 6350);
PAINT MONO (-172 6350);
FORCEPROP 2 LAST CDS_LIB standard
J 0
(200 6350);
DISPLAY INVISIBLE (200 6350);
FORCEPROP 1 LAST OFFPAGE TRUE
J 0
(525 6225);
DISPLAY 0.872340 (525 6225);
PAINT GREEN (525 6225);
DISPLAY INVISIBLE (525 6225);
FORCEPROP 1 LAST COMMENT_BODY TRUE
J 0
(325 6250);
DISPLAY 0.872340 (325 6250);
PAINT GREEN (325 6250);
DISPLAY INVISIBLE (325 6250);
FORCEPROP 2 LAST PATH I85
J 0
(-75 6400);
DISPLAY 0.680851 (-75 6400);
DISPLAY INVISIBLE (-75 6400);
FORCEADD OFFPAGE..3
R 2
(200 6300);
FORCEPROP 2 LAST $XR1 150 
J 0
(-200 6300);
DISPLAY 0.638298 (-200 6300);
PAINT MONO (-200 6300);
FORCEPROP 2 LAST $XR0 151 
J 0
(-80 6300);
DISPLAY 0.638298 (-80 6300);
PAINT MONO (-80 6300);
FORCEPROP 2 LAST CDS_LIB standard
J 0
(200 6300);
DISPLAY INVISIBLE (200 6300);
FORCEPROP 1 LAST OFFPAGE TRUE
J 2
(-125 6175);
DISPLAY 0.872340 (-125 6175);
DISPLAY INVISIBLE (-125 6175);
FORCEPROP 1 LAST COMMENT_BODY TRUE
J 2
(250 6200);
DISPLAY 0.872340 (250 6200);
PAINT GREEN (250 6200);
DISPLAY INVISIBLE (250 6200);
FORCEPROP 2 LAST PATH I86
J 0
(-100 6350);
DISPLAY 0.680851 (-100 6350);
DISPLAY INVISIBLE (-100 6350);
FORCEADD OFFPAGE..3
R 2
(175 6725);
FORCEPROP 2 LAST $XR1 151 
J 0
(-225 6725);
DISPLAY 0.638298 (-225 6725);
PAINT MONO (-225 6725);
FORCEPROP 2 LAST $XR0 150 
J 0
(-105 6725);
DISPLAY 0.638298 (-105 6725);
PAINT MONO (-105 6725);
FORCEPROP 2 LAST CDS_LIB standard
J 0
(175 6725);
PAINT MONO (175 6725);
DISPLAY INVISIBLE (175 6725);
FORCEPROP 1 LAST OFFPAGE TRUE
J 2
(-150 6600);
DISPLAY 0.872340 (-150 6600);
DISPLAY INVISIBLE (-150 6600);
FORCEPROP 1 LAST COMMENT_BODY TRUE
J 2
(225 6625);
DISPLAY 0.872340 (225 6625);
PAINT GREEN (225 6625);
DISPLAY INVISIBLE (225 6625);
FORCEPROP 2 LAST PATH I87
J 0
(225 6800);
DISPLAY 0.680851 (225 6800);
DISPLAY INVISIBLE (225 6800);
FORCEADD OFFPAGE..1
(175 6775);
FORCEPROP 2 LAST $XR1 151 
J 0
(-227 6775);
DISPLAY 0.638298 (-227 6775);
PAINT MONO (-227 6775);
FORCEPROP 2 LAST $XR0 150 
J 0
(-107 6775);
DISPLAY 0.638298 (-107 6775);
PAINT MONO (-107 6775);
FORCEPROP 2 LAST CDS_LIB standard
J 0
(175 6775);
PAINT MONO (175 6775);
DISPLAY INVISIBLE (175 6775);
FORCEPROP 1 LAST OFFPAGE TRUE
J 0
(500 6650);
DISPLAY 0.872340 (500 6650);
PAINT GREEN (500 6650);
DISPLAY INVISIBLE (500 6650);
FORCEPROP 1 LAST COMMENT_BODY TRUE
J 0
(300 6675);
DISPLAY 0.872340 (300 6675);
PAINT GREEN (300 6675);
DISPLAY INVISIBLE (300 6675);
FORCEPROP 2 LAST PATH I88
J 0
(225 6850);
DISPLAY 0.680851 (225 6850);
DISPLAY INVISIBLE (225 6850);
FORCEADD Q_RES..1
(1950 6350);
FORCEPROP 1 LAST LOCATION R4149
J 0
(1700 6350);
DISPLAY 0.638298 (1700 6350);
FORCEPROP 0 LAST $SEC 1
J 0
(2125 6500);
DISPLAY 0.680851 (2125 6500);
PAINT MONO (2125 6500);
DISPLAY INVISIBLE (2125 6500);
FORCEPROP 0 LAST CDS_SEC 1
J 0
(2125 6500);
DISPLAY 1.021277 (2125 6500);
DISPLAY INVISIBLE (2125 6500);
FORCEPROP 1 LASTPIN (1850 6350) $PN 1
J 0
(1862 6362);
DISPLAY 0.787234 (1862 6362);
PAINT MONO (1862 6362);
FORCEPROP 1 LASTPIN (2050 6350) $PN 2
J 0
(2012 6362);
DISPLAY 0.787234 (2012 6362);
PAINT MONO (2012 6362);
FORCEPROP 1 LAST TOLERANCE 1%
J 0
(2175 6350);
DISPLAY 0.510638 (2175 6350);
FORCEPROP 1 LAST VALUE 33.2
J 2
(2150 6350);
DISPLAY 0.510638 (2150 6350);
FORCEPROP 1 LAST WATTAGE 1/16W
J 2
(2125 6475);
DISPLAY 0.510638 (2125 6475);
FORCEPROP 1 LAST PACK_TYPE 0402LF
J 0
(1825 6475);
DISPLAY 0.510638 (1825 6475);
FORCEPROP 1 LAST MATERIAL CHIP
J 0
(2250 6350);
DISPLAY 0.510638 (2250 6350);
FORCEPROP 2 LAST CDS_LIB pure_quanta
J 0
(1950 6350);
DISPLAY INVISIBLE (1950 6350);
FORCEPROP 1 LAST PART_NUMBER CS03322FB03
J 0
(1825 6425);
DISPLAY 0.510638 (1825 6425);
DISPLAY INVISIBLE (1825 6425);
FORCEPROP 1 LAST PATH I89
J 0
(1900 6500);
DISPLAY 0.978723 (1900 6500);
PAINT WHITE (1900 6500);
DISPLAY INVISIBLE (1900 6500);
FORCEADD Q_RES..1
(-525 2000);
FORCEPROP 1 LAST LOCATION R1494
J 0
(-700 2000);
DISPLAY 0.489362 (-700 2000);
PAINT SKYBLUE (-700 2000);
FORCEPROP 0 LAST $SEC 1
J 0
(-325 2025);
DISPLAY 0.680851 (-325 2025);
PAINT MONO (-325 2025);
DISPLAY INVISIBLE (-325 2025);
FORCEPROP 0 LAST CDS_SEC 1
J 0
(-325 2025);
DISPLAY 0.680851 (-325 2025);
DISPLAY INVISIBLE (-325 2025);
FORCEPROP 1 LASTPIN (-625 2000) $PN 1
J 0
(-613 2012);
DISPLAY 0.489362 (-613 2012);
PAINT MONO (-613 2012);
FORCEPROP 1 LASTPIN (-425 2000) $PN 2
J 0
(-463 2012);
DISPLAY 0.489362 (-463 2012);
PAINT MONO (-463 2012);
FORCEPROP 1 LAST VALUE 33
J 2
(-325 2000);
DISPLAY 0.489362 (-325 2000);
PAINT SKYBLUE (-325 2000);
FORCEPROP 1 LAST PACK_TYPE 0402LF
J 0
(-475 1925);
DISPLAY 0.489362 (-475 1925);
PAINT SKYBLUE (-475 1925);
DISPLAY INVISIBLE (-475 1925);
FORCEPROP 1 LAST TOLERANCE 5%
J 0
(-550 1925);
DISPLAY 0.489362 (-550 1925);
PAINT SKYBLUE (-550 1925);
DISPLAY INVISIBLE (-550 1925);
FORCEPROP 1 LAST MATERIAL CHIP
J 0
(-100 1925);
DISPLAY 0.489362 (-100 1925);
PAINT SKYBLUE (-100 1925);
DISPLAY INVISIBLE (-100 1925);
FORCEPROP 1 LAST WATTAGE 1/16W
J 2
(-125 1925);
DISPLAY 0.489362 (-125 1925);
PAINT SKYBLUE (-125 1925);
DISPLAY INVISIBLE (-125 1925);
FORCEPROP 2 LAST CDS_LIB pure_quanta
J 0
(-525 2000);
DISPLAY INVISIBLE (-525 2000);
FORCEPROP 1 LAST PART_NUMBER CS03302JB10
J 0
(-500 2050);
DISPLAY 0.489362 (-500 2050);
PAINT SKYBLUE (-500 2050);
DISPLAY INVISIBLE (-500 2050);
FORCEPROP 1 LAST PATH I9
J 0
(-575 2150);
DISPLAY 0.978723 (-575 2150);
PAINT WHITE (-575 2150);
DISPLAY INVISIBLE (-575 2150);
FORCEADD Q_RES..1
(1950 6300);
FORCEPROP 1 LAST LOCATION R4150
J 0
(1700 6300);
DISPLAY 0.638298 (1700 6300);
FORCEPROP 0 LAST $SEC 1
J 0
(1775 6350);
DISPLAY 0.680851 (1775 6350);
PAINT MONO (1775 6350);
DISPLAY INVISIBLE (1775 6350);
FORCEPROP 0 LAST CDS_SEC 1
J 0
(1775 6350);
DISPLAY 1.021277 (1775 6350);
DISPLAY INVISIBLE (1775 6350);
FORCEPROP 1 LASTPIN (1850 6300) $PN 1
J 0
(1862 6312);
DISPLAY 0.787234 (1862 6312);
PAINT MONO (1862 6312);
FORCEPROP 1 LASTPIN (2050 6300) $PN 2
J 0
(2012 6312);
DISPLAY 0.787234 (2012 6312);
PAINT MONO (2012 6312);
FORCEPROP 1 LAST VALUE 33.2
J 2
(2150 6300);
DISPLAY 0.510638 (2150 6300);
FORCEPROP 1 LAST TOLERANCE 1%
J 0
(2175 6300);
DISPLAY 0.510638 (2175 6300);
FORCEPROP 1 LAST MATERIAL CHIP
J 0
(2250 6300);
DISPLAY 0.510638 (2250 6300);
FORCEPROP 1 LAST PACK_TYPE 0402LF
J 0
(2300 6300);
DISPLAY 0.638298 (2300 6300);
DISPLAY INVISIBLE (2300 6300);
FORCEPROP 1 LAST WATTAGE 1/16W
J 2
(2150 6400);
DISPLAY 0.638298 (2150 6400);
DISPLAY INVISIBLE (2150 6400);
FORCEPROP 2 LAST CDS_LIB pure_quanta
J 0
(1950 6300);
DISPLAY INVISIBLE (1950 6300);
FORCEPROP 1 LAST PART_NUMBER CS03322FB03
J 0
(1825 6350);
DISPLAY 0.638298 (1825 6350);
DISPLAY INVISIBLE (1825 6350);
FORCEPROP 1 LAST PATH I90
J 0
(1900 6450);
DISPLAY 0.978723 (1900 6450);
PAINT WHITE (1900 6450);
DISPLAY INVISIBLE (1900 6450);
FORCEADD Q_RES..1
(1925 6775);
FORCEPROP 1 LAST LOCATION R2995
J 0
(1675 6775);
DISPLAY 0.808511 (1675 6775);
FORCEPROP 0 LAST $SEC 1
J 0
(2100 6925);
DISPLAY 0.680851 (2100 6925);
PAINT MONO (2100 6925);
DISPLAY INVISIBLE (2100 6925);
FORCEPROP 0 LAST CDS_SEC 1
J 0
(2100 6925);
DISPLAY 1.021277 (2100 6925);
DISPLAY INVISIBLE (2100 6925);
FORCEPROP 1 LASTPIN (1825 6775) $PN 1
J 0
(1837 6787);
DISPLAY 0.787234 (1837 6787);
FORCEPROP 1 LASTPIN (2025 6775) $PN 2
J 0
(1987 6787);
DISPLAY 0.787234 (1987 6787);
FORCEPROP 1 LAST WATTAGE 1/16W
J 2
(2100 6900);
DISPLAY 0.510638 (2100 6900);
FORCEPROP 1 LAST TOLERANCE 1%
J 0
(2150 6775);
DISPLAY 0.510638 (2150 6775);
FORCEPROP 1 LAST VALUE 33.2
J 2
(2125 6775);
DISPLAY 0.510638 (2125 6775);
FORCEPROP 1 LAST PACK_TYPE 0402LF
J 0
(1800 6900);
DISPLAY 0.510638 (1800 6900);
FORCEPROP 1 LAST MATERIAL CHIP
J 0
(2225 6775);
DISPLAY 0.510638 (2225 6775);
FORCEPROP 2 LAST CDS_LIB pure_quanta
J 0
(1925 6775);
DISPLAY INVISIBLE (1925 6775);
FORCEPROP 1 LAST PART_NUMBER CS03322FB03
J 0
(1800 6850);
DISPLAY 0.510638 (1800 6850);
DISPLAY INVISIBLE (1800 6850);
FORCEPROP 1 LAST PATH I91
J 0
(1875 6925);
DISPLAY 0.978723 (1875 6925);
PAINT WHITE (1875 6925);
DISPLAY INVISIBLE (1875 6925);
FORCEADD Q_RES..1
(1925 6725);
FORCEPROP 1 LAST LOCATION R2996
J 0
(1675 6725);
DISPLAY 0.808511 (1675 6725);
FORCEPROP 0 LAST $SEC 1
J 0
(1675 6775);
DISPLAY 0.680851 (1675 6775);
PAINT MONO (1675 6775);
DISPLAY INVISIBLE (1675 6775);
FORCEPROP 0 LAST CDS_SEC 1
J 0
(1675 6775);
DISPLAY 1.021277 (1675 6775);
DISPLAY INVISIBLE (1675 6775);
FORCEPROP 1 LASTPIN (1825 6725) $PN 1
J 0
(1837 6737);
DISPLAY 0.787234 (1837 6737);
FORCEPROP 1 LASTPIN (2025 6725) $PN 2
J 0
(1987 6737);
DISPLAY 0.787234 (1987 6737);
FORCEPROP 1 LAST MATERIAL CHIP
J 0
(2225 6725);
DISPLAY 0.510638 (2225 6725);
FORCEPROP 1 LAST VALUE 33.2
J 2
(2125 6725);
DISPLAY 0.510638 (2125 6725);
FORCEPROP 1 LAST TOLERANCE 1%
J 0
(2150 6725);
DISPLAY 0.510638 (2150 6725);
FORCEPROP 2 LAST CDS_LIB pure_quanta
J 0
(1925 6725);
DISPLAY INVISIBLE (1925 6725);
FORCEPROP 1 LAST WATTAGE 1/16W
J 2
(2125 6825);
DISPLAY 0.638298 (2125 6825);
DISPLAY INVISIBLE (2125 6825);
FORCEPROP 1 LAST PACK_TYPE 0402LF
J 0
(2275 6725);
DISPLAY 0.638298 (2275 6725);
DISPLAY INVISIBLE (2275 6725);
FORCEPROP 1 LAST PART_NUMBER CS03322FB03
J 0
(1800 6775);
DISPLAY 0.638298 (1800 6775);
DISPLAY INVISIBLE (1800 6775);
FORCEPROP 1 LAST PATH I92
J 0
(1875 6875);
DISPLAY 0.978723 (1875 6875);
PAINT WHITE (1875 6875);
DISPLAY INVISIBLE (1875 6875);
FORCEADD OFFPAGE..5
(3050 4125);
FORCEPROP 2 LAST $XR1 241 
J 0
(2645 4125);
DISPLAY 0.638298 (2645 4125);
PAINT MONO (2645 4125);
FORCEPROP 2 LAST $XR0 150 
J 0
(2765 4125);
DISPLAY 0.638298 (2765 4125);
PAINT MONO (2765 4125);
FORCEPROP 2 LAST CDS_LIB standard
J 0
(3050 4125);
DISPLAY INVISIBLE (3050 4125);
FORCEPROP 1 LAST OFFPAGE TRUE
J 0
(3375 4000);
DISPLAY 0.872340 (3375 4000);
PAINT GREEN (3375 4000);
DISPLAY INVISIBLE (3375 4000);
FORCEPROP 1 LAST COMMENT_BODY TRUE
J 0
(3150 4050);
DISPLAY 0.872340 (3150 4050);
PAINT PEACH (3150 4050);
DISPLAY INVISIBLE (3150 4050);
FORCEPROP 2 LAST PATH I93
J 0
(2775 4175);
DISPLAY 0.680851 (2775 4175);
DISPLAY INVISIBLE (2775 4175);
FORCEADD OFFPAGE..5
(3050 4175);
FORCEPROP 2 LAST $XR1 241 
J 0
(2645 4175);
DISPLAY 0.638298 (2645 4175);
PAINT MONO (2645 4175);
FORCEPROP 2 LAST $XR0 150 
J 0
(2765 4175);
DISPLAY 0.638298 (2765 4175);
PAINT MONO (2765 4175);
FORCEPROP 2 LAST CDS_LIB standard
J 0
(3050 4175);
DISPLAY INVISIBLE (3050 4175);
FORCEPROP 1 LAST OFFPAGE TRUE
J 0
(3375 4050);
DISPLAY 0.872340 (3375 4050);
PAINT GREEN (3375 4050);
DISPLAY INVISIBLE (3375 4050);
FORCEPROP 1 LAST COMMENT_BODY TRUE
J 0
(3150 4100);
DISPLAY 0.872340 (3150 4100);
PAINT PEACH (3150 4100);
DISPLAY INVISIBLE (3150 4100);
FORCEPROP 2 LAST PATH I94
J 0
(2775 4225);
DISPLAY 0.680851 (2775 4225);
DISPLAY INVISIBLE (2775 4225);
FORCEADD OFFPAGE..3
R 2
(3075 4475);
FORCEPROP 2 LAST $XR1 150 
J 0
(2645 4475);
DISPLAY 0.638298 (2645 4475);
PAINT MONO (2645 4475);
FORCEPROP 2 LAST $XR0 151 
J 0
(2765 4475);
DISPLAY 0.638298 (2765 4475);
PAINT MONO (2765 4475);
FORCEPROP 2 LAST CDS_LIB standard
J 0
(3075 4475);
DISPLAY INVISIBLE (3075 4475);
FORCEPROP 1 LAST OFFPAGE TRUE
J 2
(2750 4350);
DISPLAY 0.872340 (2750 4350);
DISPLAY INVISIBLE (2750 4350);
FORCEPROP 1 LAST COMMENT_BODY TRUE
J 2
(3125 4375);
DISPLAY 0.872340 (3125 4375);
PAINT GREEN (3125 4375);
DISPLAY INVISIBLE (3125 4375);
FORCEPROP 2 LAST PATH I95
J 0
(3125 4550);
DISPLAY 0.680851 (3125 4550);
DISPLAY INVISIBLE (3125 4550);
FORCEADD OFFPAGE..1
(3075 4525);
FORCEPROP 2 LAST $XR1 151 
J 0
(2673 4525);
DISPLAY 0.638298 (2673 4525);
PAINT MONO (2673 4525);
FORCEPROP 2 LAST $XR0 150 
J 0
(2793 4525);
DISPLAY 0.638298 (2793 4525);
PAINT MONO (2793 4525);
FORCEPROP 2 LAST CDS_LIB standard
J 0
(3075 4525);
DISPLAY INVISIBLE (3075 4525);
FORCEPROP 1 LAST OFFPAGE TRUE
J 0
(3400 4400);
DISPLAY 0.872340 (3400 4400);
PAINT GREEN (3400 4400);
DISPLAY INVISIBLE (3400 4400);
FORCEPROP 1 LAST COMMENT_BODY TRUE
J 0
(3200 4425);
DISPLAY 0.872340 (3200 4425);
PAINT GREEN (3200 4425);
DISPLAY INVISIBLE (3200 4425);
FORCEPROP 2 LAST PATH I96
J 0
(3125 4600);
DISPLAY 0.680851 (3125 4600);
DISPLAY INVISIBLE (3125 4600);
FORCEADD OFFPAGE..5
(3050 4725);
FORCEPROP 2 LAST $XR1 151 
J 0
(2645 4725);
DISPLAY 0.638298 (2645 4725);
PAINT MONO (2645 4725);
FORCEPROP 2 LAST $XR0 150 
J 0
(2765 4725);
DISPLAY 0.638298 (2765 4725);
PAINT MONO (2765 4725);
FORCEPROP 2 LAST CDS_LIB standard
J 0
(3050 4725);
PAINT MONO (3050 4725);
DISPLAY INVISIBLE (3050 4725);
FORCEPROP 1 LAST OFFPAGE TRUE
J 0
(3375 4600);
DISPLAY 0.872340 (3375 4600);
PAINT GREEN (3375 4600);
DISPLAY INVISIBLE (3375 4600);
FORCEPROP 1 LAST COMMENT_BODY TRUE
J 0
(3150 4650);
DISPLAY 0.872340 (3150 4650);
PAINT PEACH (3150 4650);
DISPLAY INVISIBLE (3150 4650);
FORCEPROP 2 LAST PATH I97
J 0
(3100 4800);
DISPLAY 0.680851 (3100 4800);
DISPLAY INVISIBLE (3100 4800);
FORCEADD OFFPAGE..5
(3050 4775);
FORCEPROP 2 LAST $XR1 151 
J 0
(2645 4775);
DISPLAY 0.638298 (2645 4775);
PAINT MONO (2645 4775);
FORCEPROP 2 LAST $XR0 150 
J 0
(2765 4775);
DISPLAY 0.638298 (2765 4775);
PAINT MONO (2765 4775);
FORCEPROP 2 LAST CDS_LIB standard
J 0
(3050 4775);
PAINT MONO (3050 4775);
DISPLAY INVISIBLE (3050 4775);
FORCEPROP 1 LAST OFFPAGE TRUE
J 0
(3375 4650);
DISPLAY 0.872340 (3375 4650);
PAINT GREEN (3375 4650);
DISPLAY INVISIBLE (3375 4650);
FORCEPROP 1 LAST COMMENT_BODY TRUE
J 0
(3150 4700);
DISPLAY 0.872340 (3150 4700);
PAINT PEACH (3150 4700);
DISPLAY INVISIBLE (3150 4700);
FORCEPROP 2 LAST PATH I98
J 0
(3100 4850);
DISPLAY 0.680851 (3100 4850);
DISPLAY INVISIBLE (3100 4850);
FORCEADD OFFPAGE..5
(3050 4975);
FORCEPROP 2 LAST $XR1 160 
J 0
(2645 4975);
DISPLAY 0.638298 (2645 4975);
PAINT MONO (2645 4975);
FORCEPROP 2 LAST $XR0 150 
J 0
(2765 4975);
DISPLAY 0.638298 (2765 4975);
PAINT MONO (2765 4975);
FORCEPROP 2 LAST CDS_LIB standard
J 0
(3050 4975);
PAINT MONO (3050 4975);
DISPLAY INVISIBLE (3050 4975);
FORCEPROP 1 LAST OFFPAGE TRUE
J 0
(3375 4850);
DISPLAY 0.872340 (3375 4850);
PAINT GREEN (3375 4850);
DISPLAY INVISIBLE (3375 4850);
FORCEPROP 1 LAST COMMENT_BODY TRUE
J 0
(3150 4900);
DISPLAY 0.872340 (3150 4900);
PAINT PEACH (3150 4900);
DISPLAY INVISIBLE (3150 4900);
FORCEPROP 2 LAST PATH I99
J 0
(3100 5050);
DISPLAY 0.680851 (3100 5050);
DISPLAY INVISIBLE (3100 5050);
FORCEADD DNS..2
(4300 4125);
PAINT RED (4300 4125);
FORCEPROP 2 LAST CDS_LIB mstr_misc
J 0
(4300 4125);
DISPLAY INVISIBLE (4300 4125);
FORCEPROP 1 LAST COMMENT_BODY TRUE
R 1
J 0
(4375 3900);
DISPLAY 0.872340 (4375 3900);
PAINT GREEN (4375 3900);
DISPLAY INVISIBLE (4375 3900);
FORCEADD DNS..2
(4300 4175);
PAINT RED (4300 4175);
FORCEPROP 2 LAST CDS_LIB mstr_misc
J 0
(4300 4175);
DISPLAY INVISIBLE (4300 4175);
FORCEPROP 1 LAST COMMENT_BODY TRUE
R 1
J 0
(4375 3950);
DISPLAY 0.872340 (4375 3950);
PAINT GREEN (4375 3950);
DISPLAY INVISIBLE (4375 3950);
FORCEADD DNS..2
(4275 4450);
PAINT RED (4275 4450);
FORCEPROP 2 LAST CDS_LIB mstr_misc
J 0
(4275 4450);
DISPLAY INVISIBLE (4275 4450);
FORCEPROP 1 LAST COMMENT_BODY TRUE
R 1
J 0
(4350 4225);
DISPLAY 0.872340 (4350 4225);
PAINT GREEN (4350 4225);
DISPLAY INVISIBLE (4350 4225);
FORCEADD DNS..2
(4275 4550);
PAINT RED (4275 4550);
FORCEPROP 2 LAST CDS_LIB mstr_misc
J 0
(4275 4550);
DISPLAY INVISIBLE (4275 4550);
FORCEPROP 1 LAST COMMENT_BODY TRUE
R 1
J 0
(4350 4325);
DISPLAY 0.872340 (4350 4325);
PAINT GREEN (4350 4325);
DISPLAY INVISIBLE (4350 4325);
FORCEADD DNS..2
(4300 4725);
PAINT RED (4300 4725);
FORCEPROP 2 LAST CDS_LIB mstr_misc
J 0
(4300 4725);
DISPLAY INVISIBLE (4300 4725);
FORCEPROP 1 LAST COMMENT_BODY TRUE
R 1
J 0
(4375 4500);
DISPLAY 0.872340 (4375 4500);
PAINT GREEN (4375 4500);
DISPLAY INVISIBLE (4375 4500);
FORCEADD DNS..2
(4300 4975);
PAINT RED (4300 4975);
FORCEPROP 2 LAST CDS_LIB mstr_misc
J 0
(4300 4975);
DISPLAY INVISIBLE (4300 4975);
FORCEPROP 1 LAST COMMENT_BODY TRUE
R 1
J 0
(4375 4750);
DISPLAY 0.872340 (4375 4750);
PAINT GREEN (4375 4750);
DISPLAY INVISIBLE (4375 4750);
FORCEADD DNS..2
(4300 5025);
PAINT RED (4300 5025);
FORCEPROP 2 LAST CDS_LIB mstr_misc
J 0
(4300 5025);
DISPLAY INVISIBLE (4300 5025);
FORCEPROP 1 LAST COMMENT_BODY TRUE
R 1
J 0
(4375 4800);
DISPLAY 0.872340 (4375 4800);
PAINT GREEN (4375 4800);
DISPLAY INVISIBLE (4375 4800);
FORCEADD DNS..2
(4300 5225);
PAINT RED (4300 5225);
FORCEPROP 2 LAST CDS_LIB mstr_misc
J 0
(4300 5225);
DISPLAY INVISIBLE (4300 5225);
FORCEPROP 1 LAST COMMENT_BODY TRUE
R 1
J 0
(4375 5000);
DISPLAY 0.872340 (4375 5000);
PAINT GREEN (4375 5000);
DISPLAY INVISIBLE (4375 5000);
FORCEADD DNS..2
(4300 5275);
PAINT RED (4300 5275);
FORCEPROP 2 LAST CDS_LIB mstr_misc
J 0
(4300 5275);
DISPLAY INVISIBLE (4300 5275);
FORCEPROP 1 LAST COMMENT_BODY TRUE
R 1
J 0
(4375 5050);
DISPLAY 0.872340 (4375 5050);
PAINT GREEN (4375 5050);
DISPLAY INVISIBLE (4375 5050);
FORCEADD DNS..2
(4300 4775);
PAINT RED (4300 4775);
FORCEPROP 2 LAST CDS_LIB mstr_misc
J 0
(4300 4775);
DISPLAY INVISIBLE (4300 4775);
FORCEPROP 1 LAST COMMENT_BODY TRUE
R 1
J 0
(4375 4550);
DISPLAY 0.872340 (4375 4550);
PAINT GREEN (4375 4550);
DISPLAY INVISIBLE (4375 4550);
FORCEADD DNS..2
(-2150 5375);
PAINT RED (-2150 5375);
FORCEPROP 2 LAST CDS_LIB mstr_misc
J 0
(-2150 5375);
DISPLAY INVISIBLE (-2150 5375);
FORCEPROP 1 LAST COMMENT_BODY TRUE
J 0
(-2150 5375);
DISPLAY INVISIBLE (-2150 5375);
FORCEADD DNS..2
(-2125 5325);
PAINT RED (-2125 5325);
FORCEPROP 2 LAST CDS_LIB mstr_misc
J 0
(-2125 5325);
DISPLAY INVISIBLE (-2125 5325);
FORCEPROP 1 LAST COMMENT_BODY TRUE
J 0
(-2125 5325);
DISPLAY INVISIBLE (-2125 5325);
FORCEADD DNS..1
(-1150 2950);
PAINT RED (-1150 2950);
FORCEPROP 2 LAST CDS_LIB mstr_misc
J 0
(-1150 2950);
DISPLAY INVISIBLE (-1150 2950);
FORCEPROP 1 LAST COMMENT_BODY TRUE
R 1
J 0
(-1075 2725);
DISPLAY 0.872340 (-1075 2725);
PAINT GREEN (-1075 2725);
DISPLAY INVISIBLE (-1075 2725);
FORCEADD DNS..1
(-1650 4850);
PAINT RED (-1650 4850);
FORCEPROP 2 LAST CDS_LIB mstr_misc
J 0
(-1650 4850);
DISPLAY INVISIBLE (-1650 4850);
FORCEPROP 1 LAST COMMENT_BODY TRUE
R 1
J 0
(-1575 4625);
DISPLAY 0.872340 (-1575 4625);
PAINT GREEN (-1575 4625);
DISPLAY INVISIBLE (-1575 4625);
FORCEADD DNS..2
(-2125 5450);
PAINT RED (-2125 5450);
FORCEPROP 2 LAST CDS_LIB mstr_misc
J 0
(-2125 5450);
DISPLAY INVISIBLE (-2125 5450);
FORCEPROP 1 LAST COMMENT_BODY TRUE
J 0
(-2125 5450);
DISPLAY INVISIBLE (-2125 5450);
FORCEADD CAD_NOTE..1
(-1950 3825);
FORCEPROP 0 LAST L1 CO-LAY R6066 & R6067
J 0
(-2100 3700);
DISPLAY 0.617021 (-2100 3700);
PAINT WHITE (-2100 3700);
FORCEPROP 2 LAST CDS_LIB pure_quanta_power
J 0
(-1950 3825);
DISPLAY INVISIBLE (-1950 3825);
FORCEPROP 1 LAST COMMENT_BODY TRUE
J 0
(-1925 3925);
DISPLAY 0.574468 (-1925 3925);
PAINT WHITE (-1925 3925);
DISPLAY INVISIBLE (-1925 3925);
FORCEADD CAD_NOTE..1
(-1950 3250);
FORCEPROP 0 LAST L1 CO-LAY R6068 & R6069
J 0
(-2100 3125);
DISPLAY 0.617021 (-2100 3125);
PAINT WHITE (-2100 3125);
FORCEPROP 2 LAST CDS_LIB pure_quanta_power
J 0
(-1950 3250);
DISPLAY INVISIBLE (-1950 3250);
FORCEPROP 1 LAST COMMENT_BODY TRUE
J 0
(-1925 3350);
DISPLAY 0.574468 (-1925 3350);
PAINT WHITE (-1925 3350);
DISPLAY INVISIBLE (-1925 3350);
FORCEADD DNS..1
(-1125 3500);
PAINT RED (-1125 3500);
FORCEPROP 2 LAST CDS_LIB mstr_misc
J 0
(-1125 3500);
DISPLAY INVISIBLE (-1125 3500);
FORCEPROP 1 LAST COMMENT_BODY TRUE
R 1
J 0
(-1050 3275);
DISPLAY 0.872340 (-1050 3275);
PAINT GREEN (-1050 3275);
DISPLAY INVISIBLE (-1050 3275);
FORCEADD DNS..2
(-2125 5500);
PAINT RED (-2125 5500);
FORCEPROP 2 LAST CDS_LIB mstr_misc
J 0
(-2125 5500);
DISPLAY INVISIBLE (-2125 5500);
FORCEPROP 1 LAST COMMENT_BODY TRUE
J 0
(-2125 5500);
DISPLAY INVISIBLE (-2125 5500);
FORCEADD DNS..2
(-2125 5550);
PAINT RED (-2125 5550);
FORCEPROP 2 LAST CDS_LIB mstr_misc
J 0
(-2125 5550);
DISPLAY INVISIBLE (-2125 5550);
FORCEPROP 1 LAST COMMENT_BODY TRUE
J 0
(-2125 5550);
DISPLAY INVISIBLE (-2125 5550);
FORCEADD DNS..2
(-2125 5600);
PAINT RED (-2125 5600);
FORCEPROP 2 LAST CDS_LIB mstr_misc
J 0
(-2125 5600);
DISPLAY INVISIBLE (-2125 5600);
FORCEPROP 1 LAST COMMENT_BODY TRUE
J 0
(-2125 5600);
DISPLAY INVISIBLE (-2125 5600);
FORCEADD DNS..2
(-2125 5650);
PAINT RED (-2125 5650);
FORCEPROP 2 LAST CDS_LIB mstr_misc
J 0
(-2125 5650);
DISPLAY INVISIBLE (-2125 5650);
FORCEPROP 1 LAST COMMENT_BODY TRUE
J 0
(-2125 5650);
DISPLAY INVISIBLE (-2125 5650);
FORCEADD DNS..2
(-2125 5700);
PAINT RED (-2125 5700);
FORCEPROP 2 LAST CDS_LIB mstr_misc
J 0
(-2125 5700);
DISPLAY INVISIBLE (-2125 5700);
FORCEPROP 1 LAST COMMENT_BODY TRUE
J 0
(-2125 5700);
DISPLAY INVISIBLE (-2125 5700);
FORCEADD DNS..2
(-2125 5775);
PAINT RED (-2125 5775);
FORCEPROP 2 LAST CDS_LIB mstr_misc
J 0
(-2125 5775);
DISPLAY INVISIBLE (-2125 5775);
FORCEPROP 1 LAST COMMENT_BODY TRUE
J 0
(-2125 5775);
DISPLAY INVISIBLE (-2125 5775);
FORCEADD DNS..2
(-2125 5850);
PAINT RED (-2125 5850);
FORCEPROP 2 LAST CDS_LIB mstr_misc
J 0
(-2125 5850);
DISPLAY INVISIBLE (-2125 5850);
FORCEPROP 1 LAST COMMENT_BODY TRUE
J 0
(-2125 5850);
DISPLAY INVISIBLE (-2125 5850);
FORCEADD DNS..2
(4525 1200);
PAINT RED (4525 1200);
FORCEPROP 2 LAST CDS_LIB mstr_misc
J 0
(4525 1200);
DISPLAY INVISIBLE (4525 1200);
FORCEPROP 1 LAST COMMENT_BODY TRUE
R 1
J 0
(4600 975);
DISPLAY 0.872340 (4600 975);
PAINT PEACH (4600 975);
DISPLAY INVISIBLE (4600 975);
FORCEADD DNS..2
(4300 2075);
PAINT RED (4300 2075);
FORCEPROP 2 LAST CDS_LIB mstr_misc
J 0
(4300 2075);
DISPLAY INVISIBLE (4300 2075);
FORCEPROP 1 LAST COMMENT_BODY TRUE
R 1
J 0
(4375 1850);
DISPLAY 0.872340 (4375 1850);
PAINT GREEN (4375 1850);
DISPLAY INVISIBLE (4375 1850);
FORCEADD DNS..2
(4300 2150);
PAINT RED (4300 2150);
FORCEPROP 2 LAST CDS_LIB mstr_misc
J 0
(4300 2150);
DISPLAY INVISIBLE (4300 2150);
FORCEPROP 1 LAST COMMENT_BODY TRUE
R 1
J 0
(4375 1925);
DISPLAY 0.872340 (4375 1925);
PAINT GREEN (4375 1925);
DISPLAY INVISIBLE (4375 1925);
FORCEADD DNS..2
(4300 2425);
PAINT RED (4300 2425);
FORCEPROP 2 LAST CDS_LIB mstr_misc
J 0
(4300 2425);
DISPLAY INVISIBLE (4300 2425);
FORCEPROP 1 LAST COMMENT_BODY TRUE
R 1
J 0
(4375 2200);
DISPLAY 0.872340 (4375 2200);
PAINT GREEN (4375 2200);
DISPLAY INVISIBLE (4375 2200);
FORCEADD DNS..2
(4300 2650);
PAINT RED (4300 2650);
FORCEPROP 2 LAST CDS_LIB mstr_misc
J 0
(4300 2650);
DISPLAY INVISIBLE (4300 2650);
FORCEPROP 1 LAST COMMENT_BODY TRUE
R 1
J 0
(4375 2425);
DISPLAY 0.872340 (4375 2425);
PAINT GREEN (4375 2425);
DISPLAY INVISIBLE (4375 2425);
FORCEADD DNS..2
(4300 2700);
PAINT RED (4300 2700);
FORCEPROP 2 LAST CDS_LIB mstr_misc
J 0
(4300 2700);
DISPLAY INVISIBLE (4300 2700);
FORCEPROP 1 LAST COMMENT_BODY TRUE
R 1
J 0
(4375 2475);
DISPLAY 0.872340 (4375 2475);
PAINT GREEN (4375 2475);
DISPLAY INVISIBLE (4375 2475);
FORCEADD DNS..2
(4300 3050);
PAINT RED (4300 3050);
FORCEPROP 2 LAST CDS_LIB mstr_misc
J 0
(4300 3050);
DISPLAY INVISIBLE (4300 3050);
FORCEPROP 1 LAST COMMENT_BODY TRUE
R 1
J 0
(4375 2825);
DISPLAY 0.872340 (4375 2825);
PAINT GREEN (4375 2825);
DISPLAY INVISIBLE (4375 2825);
FORCEADD DNS..2
(4300 3100);
PAINT RED (4300 3100);
FORCEPROP 2 LAST CDS_LIB mstr_misc
J 0
(4300 3100);
DISPLAY INVISIBLE (4300 3100);
FORCEPROP 1 LAST COMMENT_BODY TRUE
R 1
J 0
(4375 2875);
DISPLAY 0.872340 (4375 2875);
PAINT GREEN (4375 2875);
DISPLAY INVISIBLE (4375 2875);
FORCEADD DNS..2
(4300 3425);
PAINT RED (4300 3425);
FORCEPROP 2 LAST CDS_LIB mstr_misc
J 0
(4300 3425);
DISPLAY INVISIBLE (4300 3425);
FORCEPROP 1 LAST COMMENT_BODY TRUE
R 1
J 0
(4375 3200);
DISPLAY 0.872340 (4375 3200);
PAINT GREEN (4375 3200);
DISPLAY INVISIBLE (4375 3200);
FORCEADD DNS..2
(4300 3475);
PAINT RED (4300 3475);
FORCEPROP 2 LAST CDS_LIB mstr_misc
J 0
(4300 3475);
DISPLAY INVISIBLE (4300 3475);
FORCEPROP 1 LAST COMMENT_BODY TRUE
R 1
J 0
(4375 3250);
DISPLAY 0.872340 (4375 3250);
PAINT GREEN (4375 3250);
DISPLAY INVISIBLE (4375 3250);
FORCEADD DNS..2
(4300 3725);
PAINT RED (4300 3725);
FORCEPROP 2 LAST CDS_LIB mstr_misc
J 0
(4300 3725);
DISPLAY INVISIBLE (4300 3725);
FORCEPROP 1 LAST COMMENT_BODY TRUE
R 1
J 0
(4375 3500);
DISPLAY 0.872340 (4375 3500);
PAINT GREEN (4375 3500);
DISPLAY INVISIBLE (4375 3500);
FORCEADD DNS..2
(4300 3775);
PAINT RED (4300 3775);
FORCEPROP 2 LAST CDS_LIB mstr_misc
J 0
(4300 3775);
DISPLAY INVISIBLE (4300 3775);
FORCEPROP 1 LAST COMMENT_BODY TRUE
R 1
J 0
(4375 3550);
DISPLAY 0.872340 (4375 3550);
PAINT GREEN (4375 3550);
DISPLAY INVISIBLE (4375 3550);
FORCEADD DNS..2
(5475 5875);
PAINT RED (5475 5875);
FORCEPROP 2 LAST CDS_LIB mstr_misc
J 0
(5475 5875);
DISPLAY INVISIBLE (5475 5875);
FORCEPROP 1 LAST COMMENT_BODY TRUE
R 1
J 0
(5550 5650);
DISPLAY 0.872340 (5550 5650);
PAINT PEACH (5550 5650);
DISPLAY INVISIBLE (5550 5650);
FORCEADD DNS..2
(5675 5875);
PAINT RED (5675 5875);
FORCEPROP 2 LAST CDS_LIB mstr_misc
J 0
(5675 5875);
DISPLAY INVISIBLE (5675 5875);
FORCEPROP 1 LAST COMMENT_BODY TRUE
R 1
J 0
(5750 5650);
DISPLAY 0.872340 (5750 5650);
PAINT PEACH (5750 5650);
DISPLAY INVISIBLE (5750 5650);
FORCEADD DNS..2
(5475 6350);
PAINT RED (5475 6350);
FORCEPROP 2 LAST CDS_LIB mstr_misc
J 0
(5475 6350);
DISPLAY INVISIBLE (5475 6350);
FORCEPROP 1 LAST COMMENT_BODY TRUE
R 1
J 0
(5550 6125);
DISPLAY 0.872340 (5550 6125);
PAINT PEACH (5550 6125);
DISPLAY INVISIBLE (5550 6125);
FORCEADD DNS..2
(5675 6350);
PAINT RED (5675 6350);
FORCEPROP 2 LAST CDS_LIB mstr_misc
J 0
(5675 6350);
DISPLAY INVISIBLE (5675 6350);
FORCEPROP 1 LAST COMMENT_BODY TRUE
R 1
J 0
(5750 6125);
DISPLAY 0.872340 (5750 6125);
PAINT PEACH (5750 6125);
DISPLAY INVISIBLE (5750 6125);
FORCEADD DNS..2
(4300 2350);
PAINT RED (4300 2350);
FORCEPROP 2 LAST CDS_LIB mstr_misc
J 0
(4300 2350);
DISPLAY INVISIBLE (4300 2350);
FORCEPROP 1 LAST COMMENT_BODY TRUE
R 1
J 0
(4375 2125);
DISPLAY 0.872340 (4375 2125);
PAINT GREEN (4375 2125);
DISPLAY INVISIBLE (4375 2125);
FORCEADD QUANTA_TITLE_BLOCK_C..1
(6175 325);
FORCEPROP 0 LAST CDS_CON_LAST_MODIFIED Thu Sep 14 16:12:33 2023
J 0
(4290 340);
PAINT MONO (4290 340);
DISPLAY INVISIBLE (4290 340);
FORCEPROP 2 LAST CUSTOM_TXT_CDS <XR_PAGE_TITLE>
J 0
(-1715 5575);
DISPLAY 0.638298 (-1715 5575);
PAINT PINK (-1715 5575);
DISPLAY INVISIBLE (-1715 5575);
FORCEPROP 2 LAST CUSTOM_TXT_CDS <NAME_2>
J 0
(3000 375);
FORCEPROP 2 LAST CUSTOM_TXT_CDS <Q_REV>
J 0
(5991 428);
DISPLAY 1.212766 (5991 428);
FORCEPROP 2 LAST CUSTOM_TXT_CDS <CON_PAGE_NUM> OF <CON_TOTAL_PAGES>
J 0
(5729 343);
DISPLAY 0.978723 (5729 343);
FORCEPROP 2 LAST CUSTOM_TXT_CDS <Q_PROJ>
J 0
(3793 427);
DISPLAY 1.212766 (3793 427);
FORCEPROP 2 LAST CUSTOM_TXT_CDS <Q_NUMBER>
J 0
(4772 428);
DISPLAY 1.212766 (4772 428);
FORCEPROP 2 LAST CUSTOM_TXT_CDS <NAME_1>
J 0
(3000 500);
FORCEPROP 2 LAST CUSTOM_TXT_CDS <CON_LAST_MODIFIED>
J 0
(4290 340);
DISPLAY 0.978723 (4290 340);
FORCEPROP 1 LAST Q_TITLE SCM SMBUS BUS
J 0
(-3091 326);
DISPLAY 2.446809 (-3091 326);
PAINT GREEN (-3091 326);
FORCEPROP 2 LAST CDS_LIB pure_quanta
J 0
(6175 325);
PAINT MONO (6175 325);
DISPLAY INVISIBLE (6175 325);
FORCEPROP 1 LAST CDS_LMAN_SYM_OUTLINE -9475,6775,100,-125
J 0
(6175 325);
DISPLAY 0.468085 (6175 325);
PAINT GREEN (6175 325);
DISPLAY INVISIBLE (6175 325);
FORCEPROP 2 LAST PAGE_BORDER TRUE
J 0
(-1715 5575);
DISPLAY 0.638298 (-1715 5575);
PAINT PINK (-1715 5575);
DISPLAY INVISIBLE (-1715 5575);
FORCEPROP 2 LAST CDS_XR_PAGE_TITLE CR-151 : @T6G_MB_LIB.T6G(SCH_1):PAGE151
J 0
(-1715 5575);
DISPLAY 0.638298 (-1715 5575);
PAINT PINK (-1715 5575);
DISPLAY INVISIBLE (-1715 5575);
FORCEPROP 1 LAST COMMENT_BODY TRUE
J 0
(6187 312);
DISPLAY 0.978723 (6187 312);
PAINT GREEN (6187 312);
DISPLAY INVISIBLE (6187 312);
FORCEPROP 1 LAST Q_DEPT CCBU
J 1
(2412 374);
DISPLAY 1.957447 (2412 374);
PAINT GREEN (2412 374);
DISPLAY INVISIBLE (2412 374);
WIRE 16 -1 (4250 1175)(4250 1125);
WIRE 16 -1 (4450 1325)(4450 1400);
WIRE 16 -1 (4850 1650)(5125 1650);
WIRE 16 -1 (4850 1650)(4850 1350);
WIRE 16 -1 (4675 1400)(4675 1300);
WIRE 16 -1 (-1575 6375)(-2050 6375);
WIRE 16 -1 (-2050 6375)(-2050 6600);
WIRE 16 -1 (-1375 6375)(-975 6375);
WIRE 16 -1 (-975 6375)(-975 6625);
WIRE 16 -1 (4050 1175)(4050 1125);
WIRE 16 -1 (4175 3725)(2825 3725);
FORCEPROP 0 LAST CDS_PHYS_NET_NAME I3C_BMC_SWB_SDA
J 0
(3040 3773);
PAINT MONO (3040 3773);
DISPLAY INVISIBLE (3040 3773);
FORCEPROP 2 LAST SIG_NAME I3C_BMC_SWB_SDA
J 0
(2940 3735);
DISPLAY 0.638298 (2940 3735);
PAINT WHITE (2940 3735);
WIRE 16 -1 (4175 3775)(2825 3775);
FORCEPROP 0 LAST CDS_PHYS_NET_NAME I3C_BMC_SWB_SCL
J 0
(3040 3823);
PAINT MONO (3040 3823);
DISPLAY INVISIBLE (3040 3823);
FORCEPROP 2 LAST SIG_NAME I3C_BMC_SWB_SCL
J 0
(2940 3785);
DISPLAY 0.638298 (2940 3785);
PAINT WHITE (2940 3785);
WIRE 16 -1 (-2000 6000)(-1075 6000);
FORCEPROP 2 LAST SIG_NAME RST_MB_STBY_N
J 0
(-1835 6010);
DISPLAY 0.638298 (-1835 6010);
PAINT WHITE (-1835 6010);
WIRE 16 -1 (-1075 5800)(-2000 5800);
FORCEPROP 2 LAST SIG_NAME SGPIO_SCM_DO_<0>
J 0
(-1835 5810);
DISPLAY 0.638298 (-1835 5810);
PAINT WHITE (-1835 5810);
WIRE 16 -1 (-2200 6000)(-2525 6000);
WIRE 16 -1 (-2525 6025)(-2525 6000);
WIRE 16 -1 (-2525 5800)(-2525 6000);
WIRE 16 -1 (-2200 5800)(-2525 5800);
WIRE 16 -1 (-2525 5750)(-2525 5800);
WIRE 16 -1 (-2200 5750)(-2525 5750);
WIRE 16 -1 (-2525 5750)(-2525 5700);
WIRE 16 -1 (-2200 5700)(-2525 5700);
WIRE 16 -1 (-2525 5650)(-2525 5700);
WIRE 16 -1 (-2200 5650)(-2525 5650);
WIRE 16 -1 (-2525 5600)(-2525 5650);
WIRE 16 -1 (-2200 5600)(-2525 5600);
WIRE 16 -1 (-2525 5550)(-2525 5600);
WIRE 16 -1 (-2200 5550)(-2525 5550);
WIRE 16 -1 (-2525 5550)(-2525 5500);
WIRE 16 -1 (-2200 5500)(-2525 5500);
WIRE 16 -1 (-2525 5450)(-2525 5500);
WIRE 16 -1 (-2200 5450)(-2525 5450);
WIRE 16 -1 (-2525 5400)(-2525 5450);
WIRE 16 -1 (-2200 5400)(-2525 5400);
WIRE 16 -1 (-2525 5350)(-2525 5400);
WIRE 16 -1 (-2200 5350)(-2525 5350);
WIRE 16 -1 (-675 4550)(-350 4550);
WIRE 16 -1 (-675 4550)(-675 4600);
WIRE 16 -1 (-675 4600)(-350 4600);
WIRE 16 -1 (-675 4800)(-675 4600);
WIRE 16 -1 (-150 4550)(775 4550);
FORCEPROP 2 LAST SIG_NAME SMB_CPU_5_SDA
J 0
(25 4560);
DISPLAY 0.489362 (25 4560);
WIRE 16 -1 (-150 4600)(775 4600);
FORCEPROP 2 LAST SIG_NAME SMB_CPU_5_SCL
J 0
(25 4610);
DISPLAY 0.489362 (25 4610);
WIRE 16 -1 (-1500 4850)(-1225 4850);
WIRE 16 -1 (-1225 4725)(-1225 4850);
WIRE 16 -1 (5700 6450)(5700 6550);
WIRE 16 -1 (5700 6550)(5500 6550);
WIRE 16 -1 (5500 6575)(5500 6550);
WIRE 16 -1 (5500 6550)(5500 6450);
WIRE 16 -1 (5500 5775)(5500 5675);
WIRE 16 -1 (5500 5675)(5700 5675);
WIRE 16 -1 (5700 5775)(5700 5675);
WIRE 16 -1 (5700 5675)(5700 5575);
WIRE 16 -1 (4375 2075)(4825 2075);
WIRE 16 -1 (4825 2075)(4825 2125);
WIRE 16 -1 (4825 2125)(4825 2375);
WIRE 16 -1 (4375 2125)(4825 2125);
WIRE 16 -1 (4825 2375)(4825 2425);
WIRE 16 -1 (4375 2375)(4825 2375);
WIRE 16 -1 (4825 2425)(4825 2650);
WIRE 16 -1 (4375 2425)(4825 2425);
WIRE 16 -1 (4825 2700)(4825 2650);
WIRE 16 -1 (4375 2650)(4825 2650);
WIRE 16 -1 (4825 3050)(4825 2700);
WIRE 16 -1 (4375 2700)(4825 2700);
WIRE 16 -1 (4825 3100)(4825 3050);
WIRE 16 -1 (4825 3050)(4375 3050);
WIRE 16 -1 (4825 3425)(4825 3100);
WIRE 16 -1 (4375 3100)(4825 3100);
WIRE 16 -1 (4825 3475)(4825 3425);
WIRE 16 -1 (4825 3425)(4375 3425);
WIRE 16 -1 (4825 3725)(4825 3475);
WIRE 16 -1 (4375 3475)(4825 3475);
WIRE 16 -1 (4825 3775)(4825 3725);
WIRE 16 -1 (4825 3725)(4375 3725);
WIRE 16 -1 (4825 4125)(4825 3775);
WIRE 16 -1 (4375 3775)(4825 3775);
WIRE 16 -1 (4825 4125)(4825 4175);
WIRE 16 -1 (4825 4125)(4375 4125);
WIRE 16 -1 (4825 4475)(4825 4175);
WIRE 16 -1 (4375 4175)(4825 4175);
WIRE 16 -1 (4825 4525)(4825 4475);
WIRE 16 -1 (4825 4475)(4375 4475);
WIRE 16 -1 (4825 4525)(4825 4725);
WIRE 16 -1 (4825 4525)(4375 4525);
WIRE 16 -1 (4825 4725)(4825 4775);
WIRE 16 -1 (4825 4725)(4375 4725);
WIRE 16 -1 (4825 4775)(4825 4975);
WIRE 16 -1 (4825 4775)(4375 4775);
WIRE 16 -1 (4825 4975)(4825 5025);
WIRE 16 -1 (4825 4975)(4375 4975);
WIRE 16 -1 (4825 5225)(4825 5025);
WIRE 16 -1 (4825 5025)(4375 5025);
WIRE 16 -1 (4825 5225)(4825 5275);
WIRE 16 -1 (4825 5225)(4375 5225);
WIRE 16 -1 (4825 5750)(4825 5275);
WIRE 16 -1 (4825 5275)(4375 5275);
WIRE 16 -1 (2650 5475)(3575 5475);
FORCEPROP 2 LAST SIG_NAME SMB_MUX_RT_ROM_R1_SDA
J 0
(2890 5485);
DISPLAY 0.680851 (2890 5485);
WIRE 16 -1 (1325 4900)(1050 4900);
WIRE 16 -1 (1050 4900)(1050 5475);
WIRE 16 -1 (1050 5475)(1175 5475);
WIRE 16 -1 (700 5475)(1050 5475);
WIRE 16 -1 (1175 5475)(2450 5475);
FORCEPROP 0 LAST SIG_NAME SMB_HOST_CLK_3V3AUX_SDA_R1
J 0
(1540 5485);
DISPLAY 0.553191 (1540 5485);
FORCEPROP 2 LASTPROP $XRERR UNIQUE?
J 0
(1300 5485);
DISPLAY 0.638298 (1300 5485);
PAINT MONO (1300 5485);
DISPLAY INVISIBLE (1300 5485);
WIRE 16 -1 (1175 5100)(1175 5475);
WIRE 16 -1 (1175 5100)(1325 5100);
WIRE 16 -1 (2650 5525)(3575 5525);
FORCEPROP 2 LAST SIG_NAME SMB_MUX_RT_ROM_R1_SCL
J 0
(2915 5535);
DISPLAY 0.680851 (2915 5535);
WIRE 16 -1 (1850 5725)(3550 5725);
FORCEPROP 2 LAST SIG_NAME SMB_HOST_CLK_GEN2_3V3AUX_SDA
J 0
(2365 5735);
DISPLAY 0.680851 (2365 5735);
PAINT WHITE (2365 5735);
WIRE 16 -1 (1850 6350)(1600 6350);
WIRE 16 -1 (1600 6350)(250 6350);
FORCEPROP 0 LAST SIG_NAME SMB_1_PLD_3V3AUX_SCL
J 0
(340 6360);
DISPLAY 0.680851 (340 6360);
PAINT WHITE (340 6360);
WIRE 16 -1 (1600 6350)(1600 6075);
WIRE 16 -1 (1600 6075)(1850 6075);
WIRE 16 -1 (1850 5775)(3550 5775);
FORCEPROP 2 LAST SIG_NAME SMB_HOST_CLK_GEN2_3V3AUX_SCL
J 0
(2365 5785);
DISPLAY 0.680851 (2365 5785);
PAINT WHITE (2365 5785);
WIRE 16 -1 (1325 4975)(1100 4975);
WIRE 16 -1 (1100 4975)(1100 5525);
WIRE 16 -1 (1100 5525)(1275 5525);
WIRE 16 -1 (700 5525)(1100 5525);
WIRE 16 -1 (1275 5525)(2450 5525);
FORCEPROP 2 LAST SIG_NAME SMB_HOST_CLK_3V3AUX_SCL_R1
J 0
(1540 5535);
DISPLAY 0.553191 (1540 5535);
FORCEPROP 2 LASTPROP $XRERR UNIQUE?
J 0
(1300 5535);
DISPLAY 0.638298 (1300 5535);
PAINT MONO (1300 5535);
DISPLAY INVISIBLE (1300 5535);
WIRE 16 -1 (1275 5175)(1275 5525);
WIRE 16 -1 (1275 5175)(1325 5175);
WIRE 16 -1 (1850 6300)(1550 6300);
WIRE 16 -1 (1550 6300)(250 6300);
FORCEPROP 0 LAST SIG_NAME SMB_1_PLD_3V3AUX_SDA
J 0
(340 6310);
DISPLAY 0.680851 (340 6310);
PAINT WHITE (340 6310);
WIRE 16 -1 (1550 6300)(1550 6025);
WIRE 16 -1 (1550 6025)(1850 6025);
WIRE 16 -1 (2900 1125)(2350 1125);
FORCEPROP 2 LAST SIG_NAME SMB_SCM_2_R6_SCL
J 0
(2390 1135);
DISPLAY 0.489362 (2390 1135);
WIRE 16 -1 (2175 1125)(2350 1125);
WIRE 16 -1 (2350 1125)(2350 850);
WIRE 16 -1 (2350 850)(2775 850);
WIRE 16 -1 (2300 1025)(2900 1025);
FORCEPROP 2 LAST SIG_NAME SMB_SCM_2_R6_SDA
J 0
(2415 1035);
DISPLAY 0.489362 (2415 1035);
WIRE 16 -1 (2175 1025)(2300 1025);
WIRE 16 -1 (2300 1025)(2300 750);
WIRE 16 -1 (2300 750)(2775 750);
WIRE 16 -1 (-1950 1700)(-1950 2375);
WIRE 16 -1 (-1950 1700)(-1750 1700);
WIRE 16 -1 (-1725 2375)(-1950 2375);
WIRE 16 -1 (-2650 2375)(-1950 2375);
FORCEPROP 2 LAST SIG_NAME SMB_VR_3V3AUX_SCL
J 0
(-2610 2385);
DISPLAY 0.680851 (-2610 2385);
PAINT WHITE (-2610 2385);
WIRE 16 -1 (-750 2525)(-225 2525);
WIRE 16 -1 (-750 2375)(-750 2525);
WIRE 16 -1 (-650 2375)(-750 2375);
WIRE 16 -1 (-750 2375)(-750 2100);
WIRE 16 -1 (-750 2375)(-1525 2375);
FORCEPROP 2 LAST SIG_NAME SMB_VR_3V3STBY_SCL
J 0
(-1375 2385);
DISPLAY 0.489362 (-1375 2385);
WIRE 16 -1 (-750 2100)(-625 2100);
WIRE 16 -1 (-2050 1600)(-1750 1600);
WIRE 16 -1 (-2050 1600)(-2050 2275);
WIRE 16 -1 (-2050 2275)(-1725 2275);
WIRE 16 -1 (-2650 2275)(-2050 2275);
FORCEPROP 2 LAST SIG_NAME SMB_VR_3V3AUX_SDA
J 0
(-2610 2285);
DISPLAY 0.680851 (-2610 2285);
PAINT WHITE (-2610 2285);
WIRE 16 -1 (-1025 3325)(-775 3325);
WIRE 16 -1 (-775 2925)(-775 3325);
WIRE 16 -1 (-300 2925)(-775 2925);
FORCEPROP 2 LAST SIG_NAME JTAG_SCM_TDO_R
J 0
(-735 2935);
DISPLAY 0.638298 (-735 2935);
PAINT WHITE (-735 2935);
WIRE 16 -1 (-1025 2925)(-775 2925);
WIRE 16 -1 (-1350 1700)(-775 1700);
WIRE 16 -1 (-1350 1700)(-1350 1450);
WIRE 16 -1 (-1550 1700)(-1350 1700);
FORCEPROP 2 LAST SIG_NAME SMB_SCM_2_R3_SCL
J 0
(-1285 1710);
DISPLAY 0.617021 (-1285 1710);
WIRE 16 -1 (-1350 1450)(-1225 1450);
WIRE 16 -1 (250 5725)(1650 5725);
FORCEPROP 2 LAST SIG_NAME SMB_HOST_CLK_3V3AUX_SDA
J 0
(665 5735);
DISPLAY 0.638298 (665 5735);
PAINT WHITE (665 5735);
WIRE 16 -1 (200 5725)(250 5725);
WIRE 16 -1 (250 5725)(250 5475);
WIRE 16 -1 (250 5475)(500 5475);
WIRE 16 -1 (3575 6025)(2050 6025);
FORCEPROP 0 LAST SIG_NAME SMB_2_PLD_3V3AUX_SDA_R1
J 0
(2715 6035);
DISPLAY 0.680851 (2715 6035);
PAINT WHITE (2715 6035);
WIRE 16 -1 (3575 6075)(2050 6075);
FORCEPROP 0 LAST SIG_NAME SMB_2_PLD_3V3AUX_SCL_R1
J 0
(2715 6085);
DISPLAY 0.680851 (2715 6085);
PAINT WHITE (2715 6085);
WIRE 16 -1 (325 5775)(1650 5775);
FORCEPROP 2 LAST SIG_NAME SMB_HOST_CLK_3V3AUX_SCL
J 0
(665 5785);
DISPLAY 0.638298 (665 5785);
PAINT WHITE (665 5785);
WIRE 16 -1 (225 5775)(325 5775);
WIRE 16 -1 (325 5775)(325 5525);
WIRE 16 -1 (325 5525)(500 5525);
WIRE 16 -1 (1525 4975)(2200 4975);
FORCEPROP 2 LAST SIG_NAME SMB_9ZXL045_P0_SCL
J 0
(1765 4985);
DISPLAY 0.553191 (1765 4985);
WIRE 16 -1 (1525 5100)(2200 5100);
FORCEPROP 2 LAST SIG_NAME SMB_9ZXL045_P1_SDA
J 0
(1740 5110);
DISPLAY 0.553191 (1740 5110);
WIRE 16 -1 (1525 5175)(2200 5175);
FORCEPROP 2 LAST SIG_NAME SMB_9ZXL045_P1_SCL
J 0
(1740 5185);
DISPLAY 0.553191 (1740 5185);
WIRE 16 -1 (1525 4900)(2200 4900);
FORCEPROP 2 LAST SIG_NAME SMB_9ZXL045_P0_SDA
J 0
(1740 4910);
DISPLAY 0.553191 (1740 4910);
WIRE 16 -1 (4175 3475)(2825 3475);
FORCEPROP 0 LAST CDS_PHYS_NET_NAME SMB_HOST_CLK_3V3AUX_SCL
J 0
(3040 3523);
PAINT MONO (3040 3523);
DISPLAY INVISIBLE (3040 3523);
FORCEPROP 2 LAST SIG_NAME SMB_HOST_CLK_3V3AUX_SCL
J 0
(2915 3485);
DISPLAY 0.638298 (2915 3485);
PAINT WHITE (2915 3485);
WIRE 16 -1 (225 6725)(1825 6725);
FORCEPROP 2 LAST SIG_NAME SMB_PMBUS_3V3AUX_SDA
J 0
(365 6735);
DISPLAY 0.680851 (365 6735);
PAINT WHITE (365 6735);
WIRE 16 -1 (3275 6450)(2300 6450);
WIRE 16 -1 (2300 6550)(2300 6450);
WIRE 16 -1 (2300 6550)(2600 6550);
WIRE 16 -1 (2275 6550)(2300 6550);
WIRE 16 -1 (2275 6725)(2275 6550);
WIRE 16 -1 (2275 6725)(3550 6725);
FORCEPROP 2 LAST SIG_NAME SMB_SML1_PMBUS_HSC_SDA
J 0
(2540 6735);
DISPLAY 0.680851 (2540 6735);
PAINT WHITE (2540 6735);
WIRE 16 -1 (2025 6725)(2275 6725);
WIRE 16 -1 (3275 6500)(2350 6500);
WIRE 16 -1 (2350 6600)(2350 6500);
WIRE 16 -1 (2600 6600)(2350 6600);
WIRE 16 -1 (2350 6600)(2325 6600);
WIRE 16 -1 (2325 6775)(2325 6600);
WIRE 16 -1 (2325 6775)(3550 6775);
FORCEPROP 2 LAST SIG_NAME SMB_SML1_PMBUS_HSC_SCL
J 0
(2540 6785);
DISPLAY 0.680851 (2540 6785);
PAINT WHITE (2540 6785);
WIRE 16 -1 (2025 6775)(2325 6775);
WIRE 16 -1 (4175 3425)(2825 3425);
FORCEPROP 0 LAST CDS_PHYS_NET_NAME SMB_HOST_CLK_3V3AUX_SDA
J 0
(3040 3473);
PAINT MONO (3040 3473);
DISPLAY INVISIBLE (3040 3473);
FORCEPROP 2 LAST SIG_NAME SMB_HOST_CLK_3V3AUX_SDA
J 0
(2915 3435);
DISPLAY 0.638298 (2915 3435);
PAINT WHITE (2915 3435);
WIRE 16 -1 (450 3475)(175 3475);
WIRE 16 -1 (175 3475)(175 2750);
WIRE 16 -1 (175 3475)(-1025 3475);
FORCEPROP 2 LAST SIG_NAME JTAG_SCM_TDI_R
J 0
(-735 3485);
DISPLAY 0.638298 (-735 3485);
PAINT WHITE (-735 3485);
WIRE 16 -1 (175 2750)(-1025 2750);
WIRE 16 -1 (600 4300)(1375 4300);
FORCEPROP 2 LAST SIG_NAME SMB_CPU_5_SCL
J 0
(865 4310);
DISPLAY 0.489362 (865 4310);
WIRE 16 -1 (-25 2625)(800 2625);
FORCEPROP 2 LAST SIG_NAME P0V9_RETIMER_CPU1_PMSDA
J 0
(190 2635);
DISPLAY 0.553191 (190 2635);
WIRE 16 -1 (-1225 2750)(-1500 2750);
WIRE 16 -1 (-1500 2750)(-1500 2925);
WIRE 16 -1 (-1500 2925)(-1225 2925);
WIRE 16 -1 (-2025 2925)(-1500 2925);
FORCEPROP 2 LAST SIG_NAME JTAG_SCM_TDO
J 0
(-1935 2935);
DISPLAY 0.638298 (-1935 2935);
PAINT WHITE (-1935 2935);
WIRE 16 -1 (600 4200)(1350 4200);
FORCEPROP 2 LAST SIG_NAME SMB_CPU_5_SDA
J 0
(865 4210);
DISPLAY 0.489362 (865 4210);
WIRE 16 -1 (4175 5025)(3100 5025);
FORCEPROP 0 LAST SIG_NAME SMB_CPU0_CPU1_SEC_SCL
J 0
(3215 5035);
DISPLAY 0.680851 (3215 5035);
PAINT WHITE (3215 5035);
WIRE 16 -1 (4175 5225)(3100 5225);
FORCEPROP 2 LAST SIG_NAME SMB_CPU0_CPU1_APML_SDA
J 0
(3215 5235);
DISPLAY 0.680851 (3215 5235);
PAINT WHITE (3215 5235);
WIRE 16 -1 (3100 4125)(4175 4125);
FORCEPROP 0 LAST CDS_PHYS_NET_NAME SMB_FAN_3V3AUX_SDA
J 0
(3140 4173);
PAINT MONO (3140 4173);
DISPLAY INVISIBLE (3140 4173);
FORCEPROP 2 LAST SIG_NAME SMB_FAN_3V3AUX_SDA
J 0
(3215 4135);
DISPLAY 0.638298 (3215 4135);
PAINT WHITE (3215 4135);
WIRE 16 -1 (3100 4175)(4175 4175);
FORCEPROP 0 LAST CDS_PHYS_NET_NAME SMB_FAN_3V3AUX_SCL
J 0
(3140 4223);
PAINT MONO (3140 4223);
DISPLAY INVISIBLE (3140 4223);
FORCEPROP 2 LAST SIG_NAME SMB_FAN_3V3AUX_SCL
J 0
(3215 4185);
DISPLAY 0.638298 (3215 4185);
PAINT WHITE (3215 4185);
WIRE 16 -1 (4175 4725)(3100 4725);
FORCEPROP 2 LAST SIG_NAME SMB_PMBUS_3V3AUX_SDA
J 0
(3215 4735);
DISPLAY 0.680851 (3215 4735);
PAINT WHITE (3215 4735);
WIRE 16 -1 (4175 5275)(3100 5275);
FORCEPROP 2 LAST SIG_NAME SMB_CPU0_CPU1_APML_SCL
J 0
(3215 5285);
DISPLAY 0.680851 (3215 5285);
PAINT WHITE (3215 5285);
WIRE 16 -1 (4175 4975)(3100 4975);
FORCEPROP 0 LAST SIG_NAME SMB_CPU0_CPU1_SEC_SDA
J 0
(3215 4985);
DISPLAY 0.680851 (3215 4985);
PAINT WHITE (3215 4985);
WIRE 16 -1 (4175 4525)(3125 4525);
FORCEPROP 0 LAST SIG_NAME SMB_1_PLD_3V3AUX_SCL
J 0
(3215 4535);
DISPLAY 0.680851 (3215 4535);
PAINT WHITE (3215 4535);
WIRE 16 -1 (4175 4475)(3125 4475);
FORCEPROP 0 LAST SIG_NAME SMB_1_PLD_3V3AUX_SDA
J 0
(3215 4485);
DISPLAY 0.680851 (3215 4485);
PAINT WHITE (3215 4485);
WIRE 16 -1 (4175 4775)(3100 4775);
FORCEPROP 2 LAST SIG_NAME SMB_PMBUS_3V3AUX_SCL
J 0
(3215 4785);
DISPLAY 0.680851 (3215 4785);
PAINT WHITE (3215 4785);
WIRE 16 -1 (-25 2525)(800 2525);
FORCEPROP 2 LAST SIG_NAME P0V9_RETIMER_CPU1_PMSCL
J 0
(190 2535);
DISPLAY 0.553191 (190 2535);
WIRE 16 -1 (225 6775)(1825 6775);
FORCEPROP 2 LAST SIG_NAME SMB_PMBUS_3V3AUX_SCL
J 0
(365 6785);
DISPLAY 0.680851 (365 6785);
PAINT WHITE (365 6785);
WIRE 16 -1 (4450 1125)(4450 1075);
WIRE 16 -1 (4450 1075)(4675 1075);
WIRE 16 -1 (5100 1075)(4675 1075);
FORCEPROP 2 LAST SIG_NAME UART_VCC_J8
J 0
(4740 1085);
DISPLAY 0.489362 (4740 1085);
FORCEPROP 2 LASTPROP $XRERR UNIQUE?
J 0
(4500 1085);
DISPLAY 0.638298 (4500 1085);
PAINT MONO (4500 1085);
DISPLAY INVISIBLE (4500 1085);
WIRE 16 -1 (4675 1100)(4675 1075);
WIRE 16 -1 (5100 1500)(5100 1075);
WIRE 16 -1 (5125 1500)(5100 1500);
WIRE 16 -1 (5700 6250)(5700 6150);
WIRE 16 -1 (5700 6150)(4925 6150);
FORCEPROP 2 LAST SIG_NAME SCM_SPARE_1
J 0
(5065 6160);
DISPLAY 0.489362 (5065 6160);
WIRE 16 -1 (5700 5975)(5700 6150);
WIRE 16 -1 (5500 6250)(5500 6200);
WIRE 16 -1 (5500 6200)(4925 6200);
FORCEPROP 2 LAST SIG_NAME SCM_SPARE_0
J 0
(5065 6210);
DISPLAY 0.489362 (5065 6210);
WIRE 16 -1 (5500 5975)(5500 6200);
WIRE 16 -1 (-2000 5400)(-1075 5400);
FORCEPROP 2 LAST SIG_NAME SGPIO_SCM_INTR_N
J 0
(-1835 5410);
DISPLAY 0.638298 (-1835 5410);
PAINT WHITE (-1835 5410);
WIRE 16 -1 (-1700 4850)(-2425 4850);
FORCEPROP 2 LAST SIG_NAME SGPIO_SCM_RESET_N
J 0
(-2310 4860);
DISPLAY 0.638298 (-2310 4860);
PAINT WHITE (-2310 4860);
WIRE 16 -1 (-2000 5350)(-1075 5350);
FORCEPROP 2 LAST SIG_NAME JTAG_SCM_DBREQ_N
J 0
(-1835 5360);
DISPLAY 0.638298 (-1835 5360);
PAINT WHITE (-1835 5360);
WIRE 16 -1 (-1075 5450)(-2000 5450);
FORCEPROP 2 LAST SIG_NAME SGPIO_SCM_LD_<1>
J 0
(-1835 5460);
DISPLAY 0.638298 (-1835 5460);
PAINT WHITE (-1835 5460);
WIRE 16 -1 (-1075 5500)(-2000 5500);
FORCEPROP 2 LAST SIG_NAME SGPIO_SCM_DI_<1>
J 0
(-1835 5510);
DISPLAY 0.638298 (-1835 5510);
PAINT WHITE (-1835 5510);
WIRE 16 -1 (-1075 5550)(-2000 5550);
FORCEPROP 2 LAST SIG_NAME SGPIO_SCM_CLK_<1>
J 0
(-1835 5560);
DISPLAY 0.638298 (-1835 5560);
PAINT WHITE (-1835 5560);
WIRE 16 -1 (5125 1550)(4250 1550);
WIRE 16 -1 (4250 1550)(4250 1375);
WIRE 16 -1 (4250 1550)(3975 1550);
FORCEPROP 2 LAST SIG_NAME UART_CPU0_SCM_LVC3_UART1_R_RX
J 0
(4065 1560);
DISPLAY 0.489362 (4065 1560);
WIRE 16 -1 (4050 1600)(5125 1600);
FORCEPROP 2 LAST SIG_NAME UART_CPU0_SCM_LVC3_UART1_TX
J 0
(4065 1610);
DISPLAY 0.489362 (4065 1610);
WIRE 16 -1 (3975 1600)(4050 1600);
WIRE 16 -1 (4050 1600)(4050 1375);
WIRE 16 -1 (4175 2425)(2825 2425);
FORCEPROP 2 LAST SIG_NAME SMB_OCP_SFF_3V3AUX_SCL
J 0
(2915 2435);
DISPLAY 0.638298 (2915 2435);
PAINT WHITE (2915 2435);
WIRE 16 -1 (4175 2375)(2825 2375);
FORCEPROP 2 LAST SIG_NAME SMB_OCP_SFF_3V3AUX_SDA
J 0
(2915 2385);
DISPLAY 0.638298 (2915 2385);
PAINT WHITE (2915 2385);
WIRE 16 -1 (4175 3050)(2825 3050);
FORCEPROP 0 LAST CDS_PHYS_NET_NAME SMB_2_BMC_GPU_SDA
J 0
(3040 3098);
PAINT MONO (3040 3098);
DISPLAY INVISIBLE (3040 3098);
FORCEPROP 2 LAST SIG_NAME SMB_2_BMC_GPU_SDA
J 0
(2940 3060);
DISPLAY 0.638298 (2940 3060);
PAINT WHITE (2940 3060);
WIRE 16 -1 (4175 3100)(2825 3100);
FORCEPROP 0 LAST CDS_PHYS_NET_NAME SMB_2_BMC_GPU_SCL
J 0
(3040 3148);
PAINT MONO (3040 3148);
DISPLAY INVISIBLE (3040 3148);
FORCEPROP 2 LAST SIG_NAME SMB_2_BMC_GPU_SCL
J 0
(2940 3110);
DISPLAY 0.638298 (2940 3110);
PAINT WHITE (2940 3110);
WIRE 16 -1 (-1075 5750)(-2000 5750);
FORCEPROP 2 LAST SIG_NAME SGPIO_SCM_CLK_<0>
J 0
(-1835 5760);
DISPLAY 0.638298 (-1835 5760);
PAINT WHITE (-1835 5760);
WIRE 16 -1 (-1075 5650)(-2000 5650);
FORCEPROP 2 LAST SIG_NAME SGPIO_SCM_LD_<0>
J 0
(-1835 5660);
DISPLAY 0.638298 (-1835 5660);
PAINT WHITE (-1835 5660);
WIRE 16 -1 (2825 2125)(4175 2125);
FORCEPROP 0 LAST SIG_NAME SMB_OCP_V3_2_3V3AUX_SCL
J 0
(2915 2135);
DISPLAY 0.553191 (2915 2135);
PAINT WHITE (2915 2135);
WIRE 16 -1 (2825 2075)(4175 2075);
FORCEPROP 0 LAST SIG_NAME SMB_OCP_V3_2_3V3AUX_SDA
J 0
(2915 2085);
DISPLAY 0.553191 (2915 2085);
PAINT WHITE (2915 2085);
WIRE 16 -1 (-1075 5600)(-2000 5600);
FORCEPROP 2 LAST SIG_NAME SGPIO_SCM_DO_<1>
J 0
(-1835 5610);
DISPLAY 0.638298 (-1835 5610);
PAINT WHITE (-1835 5610);
WIRE 16 -1 (-1075 5700)(-2000 5700);
FORCEPROP 2 LAST SIG_NAME SGPIO_SCM_DI_<0>
J 0
(-1835 5710);
DISPLAY 0.638298 (-1835 5710);
PAINT WHITE (-1835 5710);
WIRE 16 -1 (-1450 1600)(-775 1600);
FORCEPROP 2 LAST SIG_NAME SMB_SCM_2_R3_SDA
J 0
(-1260 1610);
DISPLAY 0.617021 (-1260 1610);
WIRE 16 -1 (-1450 1600)(-1450 1350);
WIRE 16 -1 (-1550 1600)(-1450 1600);
WIRE 16 -1 (-1450 1350)(-1225 1350);
WIRE 16 -1 (-1500 3325)(-1225 3325);
WIRE 16 -1 (-1500 3475)(-1500 3325);
WIRE 16 -1 (-1500 3475)(-1225 3475);
WIRE 16 -1 (-2050 3475)(-1500 3475);
FORCEPROP 2 LAST SIG_NAME JTAG_SCM_TDI
J 0
(-1960 3485);
DISPLAY 0.638298 (-1960 3485);
PAINT WHITE (-1960 3485);
WIRE 16 -1 (-1025 1450)(-425 1450);
FORCEPROP 2 LAST SIG_NAME SMB_SCM_2_R4_SCL
J 0
(-885 1460);
DISPLAY 0.617021 (-885 1460);
WIRE 16 -1 (-1025 1350)(-425 1350);
FORCEPROP 2 LAST SIG_NAME SMB_SCM_2_R4_SDA
J 0
(-860 1360);
DISPLAY 0.617021 (-860 1360);
WIRE 16 -1 (4175 2700)(2825 2700);
FORCEPROP 0 LAST CDS_PHYS_NET_NAME SMB_1_BMC_GPU_SCL
J 0
(3040 2748);
PAINT MONO (3040 2748);
DISPLAY INVISIBLE (3040 2748);
FORCEPROP 2 LAST SIG_NAME SMB_1_BMC_GPU_SCL
J 0
(2940 2710);
DISPLAY 0.638298 (2940 2710);
PAINT WHITE (2940 2710);
WIRE 16 -1 (4175 2650)(2825 2650);
FORCEPROP 0 LAST CDS_PHYS_NET_NAME SMB_1_BMC_GPU_SDA
J 0
(3040 2698);
PAINT MONO (3040 2698);
DISPLAY INVISIBLE (3040 2698);
FORCEPROP 2 LAST SIG_NAME SMB_1_BMC_GPU_SDA
J 0
(2940 2660);
DISPLAY 0.638298 (2940 2660);
PAINT WHITE (2940 2660);
WIRE 16 -1 (2800 6550)(3800 6550);
FORCEPROP 2 LAST SIG_NAME SMB_SML1_PMBUS_HSC_R1_SDA
J 0
(3140 6560);
DISPLAY 0.553191 (3140 6560);
PAINT WHITE (3140 6560);
WIRE 16 -1 (2800 6600)(3825 6600);
FORCEPROP 2 LAST SIG_NAME SMB_SML1_PMBUS_HSC_R1_SCL
J 0
(3140 6610);
DISPLAY 0.553191 (3140 6610);
PAINT WHITE (3140 6610);
WIRE 16 -1 (1675 1025)(1975 1025);
WIRE 16 -1 (1675 1425)(1675 1025);
WIRE 16 -1 (1675 1425)(2350 1425);
FORCEPROP 2 LAST SIG_NAME SMB_SCM_2_R5_SDA
J 0
(1840 1435);
DISPLAY 0.489362 (1840 1435);
WIRE 16 -1 (1600 1425)(1675 1425);
WIRE 16 -1 (1750 1125)(1975 1125);
WIRE 16 -1 (1750 1525)(1750 1125);
WIRE 16 -1 (1750 1525)(2375 1525);
FORCEPROP 2 LAST SIG_NAME SMB_SCM_2_R5_SCL
J 0
(1865 1535);
DISPLAY 0.489362 (1865 1535);
WIRE 16 -1 (1600 1525)(1750 1525);
WIRE 16 -1 (3575 6300)(2050 6300);
FORCEPROP 0 LAST SIG_NAME SMB_1_PLD_3V3AUX_SDA_R1
J 0
(2715 6310);
DISPLAY 0.680851 (2715 6310);
PAINT WHITE (2715 6310);
WIRE 16 -1 (3575 6350)(2050 6350);
FORCEPROP 0 LAST SIG_NAME SMB_1_PLD_3V3AUX_SCL_R1
J 0
(2715 6360);
DISPLAY 0.680851 (2715 6360);
PAINT WHITE (2715 6360);
WIRE 16 -1 (300 2100)(525 2100);
WIRE 16 -1 (300 2100)(300 1850);
WIRE 16 -1 (-425 2100)(300 2100);
FORCEPROP 2 LAST SIG_NAME SMB_SCM_2_R1_SCL
J 0
(-210 2110);
DISPLAY 0.489362 (-210 2110);
WIRE 16 -1 (300 1850)(400 1850);
WIRE 16 -1 (1075 1750)(1600 1750);
WIRE 16 -1 (1075 1750)(1075 1425);
WIRE 16 -1 (600 1750)(1075 1750);
FORCEPROP 2 LAST SIG_NAME SMB_SCM_2_R2_SDA
J 0
(815 1760);
DISPLAY 0.489362 (815 1760);
WIRE 16 -1 (1075 1425)(1400 1425);
WIRE 16 -1 (1400 1525)(1175 1525);
WIRE 16 -1 (1175 1850)(1175 1525);
WIRE 16 -1 (1175 1850)(1600 1850);
WIRE 16 -1 (600 1850)(1175 1850);
FORCEPROP 2 LAST SIG_NAME SMB_SCM_2_R2_SCL
J 0
(815 1860);
DISPLAY 0.489362 (815 1860);
WIRE 16 -1 (3475 6450)(4900 6450);
FORCEPROP 2 LAST SIG_NAME SMB_MUX_RT_R1_SDA
J 0
(4340 6460);
DISPLAY 0.553191 (4340 6460);
WIRE 16 -1 (-850 2625)(-225 2625);
WIRE 16 -1 (-850 2275)(-850 2625);
WIRE 16 -1 (-675 2275)(-850 2275);
WIRE 16 -1 (-850 2275)(-1525 2275);
FORCEPROP 2 LAST SIG_NAME SMB_VR_3V3STBY_SDA
J 0
(-1375 2285);
DISPLAY 0.489362 (-1375 2285);
WIRE 16 -1 (-850 2000)(-850 2275);
WIRE 16 -1 (-850 2000)(-625 2000);
WIRE 16 -1 (225 1750)(400 1750);
WIRE 16 -1 (225 2000)(225 1750);
WIRE 16 -1 (225 2000)(525 2000);
WIRE 16 -1 (-425 2000)(225 2000);
FORCEPROP 2 LAST SIG_NAME SMB_SCM_2_R1_SDA
J 0
(-210 2010);
DISPLAY 0.489362 (-210 2010);
WIRE 16 -1 (2975 850)(3800 850);
FORCEPROP 2 LAST SIG_NAME P0V9_RETIMER_CPU0_PMSCL
J 0
(3165 860);
DISPLAY 0.553191 (3165 860);
WIRE 16 -1 (2975 750)(3800 750);
FORCEPROP 2 LAST SIG_NAME P0V9_RETIMER_CPU0_PMSDA
J 0
(3165 760);
DISPLAY 0.553191 (3165 760);
WIRE 16 -1 (3475 6500)(4900 6500);
FORCEPROP 2 LAST SIG_NAME SMB_MUX_RT_R1_SCL
J 0
(4365 6510);
DISPLAY 0.553191 (4365 6510);
WIRE 16 -1 (-450 4200)(400 4200);
FORCEPROP 2 LAST SIG_NAME SMB_CPU_5_R1_SDA
J 0
(-300 4210);
DISPLAY 0.489362 (-300 4210);
WIRE 16 -1 (-475 4300)(400 4300);
FORCEPROP 2 LAST SIG_NAME SMB_CPU_5_R1_SCL
J 0
(-300 4310);
DISPLAY 0.489362 (-300 4310);
DOT 1 (-675 4600);
DOT 1 (1175 5475);
DOT 1 (-2050 2275);
DOT 1 (-1350 1700);
DOT 1 (250 5725);
DOT 1 (1100 5525);
DOT 1 (1050 5475);
DOT 1 (1275 5525);
DOT 1 (325 5775);
DOT 1 (-850 2275);
DOT 1 (300 2100);
DOT 1 (2350 1125);
DOT 1 (2300 1025);
DOT 1 (175 3475);
DOT 1 (4825 5225);
DOT 1 (4825 4125);
DOT 1 (4825 4175);
DOT 1 (4825 4475);
DOT 1 (4825 4525);
DOT 1 (4825 4775);
DOT 1 (4825 5025);
DOT 1 (4825 5275);
DOT 1 (-1450 1600);
DOT 1 (-1950 2375);
DOT 1 (2325 6775);
DOT 1 (-775 2925);
DOT 1 (-1500 2925);
DOT 1 (-1500 3475);
DOT 1 (5500 6550);
DOT 1 (5500 6200);
DOT 1 (5700 6150);
DOT 1 (5700 5675);
DOT 1 (4825 4975);
DOT 1 (4825 4725);
DOT 1 (4825 3775);
DOT 1 (4825 3725);
DOT 1 (4825 3425);
DOT 1 (4825 3475);
DOT 1 (4825 3100);
DOT 1 (4825 3050);
DOT 1 (4825 2700);
DOT 1 (4825 2650);
DOT 1 (4825 2425);
DOT 1 (4825 2375);
DOT 1 (4825 2125);
DOT 1 (4250 1550);
DOT 1 (4675 1075);
DOT 1 (1600 6350);
DOT 1 (1550 6300);
DOT 1 (4050 1600);
DOT 1 (225 2000);
DOT 1 (-2525 5800);
DOT 1 (-2525 5750);
DOT 1 (-2525 5700);
DOT 1 (-2525 5650);
DOT 1 (-2525 5550);
DOT 1 (-2525 6000);
DOT 1 (-2525 5500);
DOT 1 (-2525 5450);
DOT 1 (-2525 5400);
DOT 1 (-2525 5600);
DOT 1 (1750 1525);
DOT 1 (1675 1425);
DOT 1 (1175 1850);
DOT 1 (1075 1750);
DOT 1 (2275 6725);
DOT 1 (2300 6550);
DOT 1 (2350 6600);
DOT 1 (-750 2375);
FORCENOTE
DEFAULT: POP R6067 & R6069, DE-POP R6066 & R6068
(-1425 3825) 0;
DISPLAY LEFT (-1425 3825);
DISPLAY 1.021277 (-1425 3825);
FORCENOTE
HSC
(3625 6825) 0;
DISPLAY LEFT (3625 6825);
DISPLAY 1.021277 (3625 6825);
PAINT SKYBLUE (3625 6825);
QUIT
